# Altium SchDoc records: PCIe_JTAG.SchDoc
|HEADER=Protel for Windows - Schematic Capture Binary File Version 5.0|Weight=1161|MinorVersion=2
|RECORD=31|FontIdCount=9|Size1=10|FontName1=Times New Roman|Size2=12|FontName2=Arial|Size3=14|FontName3=Arial|Size4=24|FontName4=Times New Roman|Size5=7|FontName5=Arial|Size6=7|FontName6=Courier New|Size7=8|FontName7=Arial|Size8=10|FontName8=Arial|Size9=12|Underline9=T|FontName9=Arial|UseMBCS=T|IsBOC=T|HotSpotGridOn=T|HotSpotGridSize=1|SheetStyle=12|SystemFont=8|BorderOn=T|SheetNumberSpaceSize=12|AreaColor=16317695|SnapGridOn=T|SnapGridSize=1|VisibleGridOn=T|VisibleGridSize=10|CustomX=2338|CustomX_Frac=58268|CustomY=1653|CustomY_Frac=54331|CustomXZones=8|CustomYZones=6|CustomMarginWidth=19|CustomMarginWidth_Frac=80000|ShowTemplateGraphics=T|TemplateFileName=C:\Users\<user>\Documents\Altium\AD20\Templates\Timecard.SchDot|Display_Unit=0
|RECORD=39|IsNotAccesible=T|OwnerPartId=-1|FileName=C:\Users\<user>\Documents\Altium\AD20\Templates\Timecard.SchDot
|RECORD=4|OwnerIndex=1|OwnerPartId=-1|Location.X=1594|Location.Y=39|Color=8388608|FontID=9|Text=timingcard.com|URL=http://timingcard.com
|RECORD=6|OwnerIndex=1|IndexInSheet=1|OwnerPartId=-1|LocationCount=2|X1=1680|Y1=35|X2=1576|Y2=35
|RECORD=4|OwnerIndex=1|IndexInSheet=2|OwnerPartId=-1|Location.X=1614|Location.X_Frac=42446|Location.Y=19|Location.Y_Frac=96838|FontID=2|Text==SheetNumber
|RECORD=4|OwnerIndex=1|IndexInSheet=3|OwnerPartId=-1|Location.X=1581|Location.X_Frac=42446|Location.Y=29|Location.Y_Frac=96838|Justification=3|FontID=7|Text=SHEET
|RECORD=4|OwnerIndex=1|IndexInSheet=4|OwnerPartId=-1|Location.X=1639|Location.X_Frac=42446|Location.Y=29|Location.Y_Frac=96838|Justification=3|FontID=7|Text=OF
|RECORD=6|OwnerIndex=1|IndexInSheet=5|OwnerPartId=-1|LineWidth=1|LocationCount=2|X1=1679|X1_Frac=42446|Y1=105|Y1_Frac=96838|X2=1576|Y2=106
|RECORD=4|OwnerIndex=1|IndexInSheet=6|OwnerPartId=-1|Location.X=1658|Location.Y=20|FontID=2|Text==SheetTotal
|RECORD=30|OwnerIndex=1|IndexInSheet=7|OwnerPartId=-1|Location.X=1578|Location.Y=53|Corner.X=1673|Corner.X_Frac=88801|Corner.Y=103|KeepAspect=T|FileName=C:\Users\<user>\Desktop\Timecard Logo\TIMECARD.jpg
|RECORD=6|OwnerIndex=1|IndexInSheet=8|OwnerPartId=-1|LineWidth=1|LocationCount=2|X1=1576|X1_Frac=3162|Y1=105|Y1_Frac=42446|X2=1576|Y2=20
|RECORD=6|OwnerIndex=1|IndexInSheet=9|OwnerPartId=-1|LocationCount=2|X1=1680|Y1=51|X2=1576|Y2=51
|RECORD=41|IndexInSheet=1|OwnerPartId=-1|Color=8388608|FontID=1|IsHidden=T|Text=*|Name=CurrentTime|ReadOnlyState=1
|RECORD=41|IndexInSheet=2|OwnerPartId=-1|Color=8388608|FontID=1|IsHidden=T|Text=*|Name=CurrentDate|ReadOnlyState=1
|RECORD=41|IndexInSheet=3|OwnerPartId=-1|Color=8388608|FontID=1|IsHidden=T|Text=*|Name=Time|ReadOnlyState=1
|RECORD=41|IndexInSheet=4|OwnerPartId=-1|Color=8388608|FontID=1|IsHidden=T|Text=*|Name=Date|ReadOnlyState=1
|RECORD=41|IndexInSheet=5|OwnerPartId=-1|Color=8388608|FontID=1|IsHidden=T|Text=*|Name=DocumentFullPathAndName|ReadOnlyState=1
|RECORD=41|IndexInSheet=6|OwnerPartId=-1|Color=8388608|FontID=1|IsHidden=T|Text=*|Name=DocumentName|ReadOnlyState=1
|RECORD=41|IndexInSheet=7|OwnerPartId=-1|Color=8388608|FontID=1|IsHidden=T|Text=*|Name=ModifiedDate|ReadOnlyState=1
|RECORD=41|IndexInSheet=8|OwnerPartId=-1|Color=8388608|FontID=1|IsHidden=T|Text=*|Name=ApprovedBy|ReadOnlyState=1
|RECORD=41|IndexInSheet=9|OwnerPartId=-1|Color=8388608|FontID=1|IsHidden=T|Text=*|Name=CheckedBy|ReadOnlyState=1
|RECORD=41|IndexInSheet=10|OwnerPartId=-1|Color=8388608|FontID=1|IsHidden=T|Text=<name>|Name=Author|ReadOnlyState=1
|RECORD=41|IndexInSheet=11|OwnerPartId=-1|Color=8388608|FontID=1|IsHidden=T|Text=*|Name=CompanyName|ReadOnlyState=1
|RECORD=41|IndexInSheet=12|OwnerPartId=-1|Color=8388608|FontID=1|IsHidden=T|Text=*|Name=DrawnBy|ReadOnlyState=1
|RECORD=41|IndexInSheet=13|OwnerPartId=-1|Color=8388608|FontID=1|IsHidden=T|Text=*|Name=Engineer|ReadOnlyState=1
|RECORD=41|IndexInSheet=14|OwnerPartId=-1|Color=8388608|FontID=1|IsHidden=T|Text=*|Name=Organization|ReadOnlyState=1
|RECORD=41|IndexInSheet=15|OwnerPartId=-1|Color=8388608|FontID=1|IsHidden=T|Text=*|Name=Address1|ReadOnlyState=1
|RECORD=41|IndexInSheet=16|OwnerPartId=-1|Color=8388608|FontID=1|IsHidden=T|Text=*|Name=Address2|ReadOnlyState=1
|RECORD=41|IndexInSheet=17|OwnerPartId=-1|Color=8388608|FontID=1|IsHidden=T|Text=*|Name=Address3|ReadOnlyState=1
|RECORD=41|IndexInSheet=18|OwnerPartId=-1|Color=8388608|FontID=1|IsHidden=T|Text=*|Name=Address4|ReadOnlyState=1
|RECORD=41|IndexInSheet=19|OwnerPartId=-1|Color=8388608|FontID=1|IsHidden=T|Text=Grandmaster PCIe & JTAG Connectors|Name=Title|ReadOnlyState=1
|RECORD=41|IndexInSheet=20|OwnerPartId=-1|Color=8388608|FontID=1|IsHidden=T|Text=*|Name=DocumentNumber|ReadOnlyState=1
|RECORD=41|IndexInSheet=21|OwnerPartId=-1|Color=8388608|FontID=1|IsHidden=T|Text=A|Name=Revision|ReadOnlyState=1
|RECORD=41|IndexInSheet=22|OwnerPartId=-1|Color=8388608|FontID=1|IsHidden=T|Text=3|Name=SheetNumber|ReadOnlyState=1
|RECORD=41|IndexInSheet=23|OwnerPartId=-1|Color=8388608|FontID=1|IsHidden=T|Text=7|Name=SheetTotal|ReadOnlyState=1
|RECORD=41|IndexInSheet=24|OwnerPartId=-1|Color=8388608|FontID=1|IsHidden=T|Text=*|Name=Rule|ReadOnlyState=1
|RECORD=41|IndexInSheet=25|OwnerPartId=-1|Color=8388608|FontID=1|IsHidden=T|Text=*|Name=ImagePath|ReadOnlyState=1
|RECORD=41|IndexInSheet=26|OwnerPartId=-1|Color=8388608|FontID=1|IsHidden=T|Text=*|Name=ProjectName|ReadOnlyState=1
|RECORD=41|IndexInSheet=27|OwnerPartId=-1|Color=8388608|FontID=1|IsHidden=T|Text=*|Name=Application_BuildNumber|ReadOnlyState=1
|RECORD=41|IndexInSheet=28|OwnerPartId=-1|Location.X=21474|Location.X_Frac=83647|Location.Y=21464|Location.Y_Frac=83647|Color=8388608|FontID=1|IsHidden=T|Text=01910|Name=Customer
|RECORD=41|IndexInSheet=29|OwnerPartId=-1|Location.X=1000|Location.Y=10|Color=8388608|FontID=1|IsHidden=T|Text=*|Name=DocStatus
|RECORD=17|IndexInSheet=30|OwnerPartId=-1|Style=4|ShowNetName=T|Location.X=740|Location.Y=600|Orientation=3|Color=128|FontID=1|Text=GND
|RECORD=17|IndexInSheet=31|OwnerPartId=-1|Style=4|ShowNetName=T|Location.X=940|Location.Y=600|Orientation=3|Color=128|FontID=1|Text=GND
|RECORD=17|IndexInSheet=32|OwnerPartId=-1|ShowNetName=T|Location.X=670|Location.Y=970|Orientation=1|Color=128|FontID=1|Text=+12V_PCIE
|RECORD=17|IndexInSheet=33|OwnerPartId=-1|ShowNetName=T|Location.X=540|Location.Y=970|Orientation=1|Color=128|FontID=1|Text=+3.3V_PCIE
|RECORD=17|IndexInSheet=34|OwnerPartId=-1|ShowNetName=T|Location.X=1060|Location.Y=920|Orientation=1|Color=128|FontID=1|Text=+3.3V
|RECORD=17|IndexInSheet=35|OwnerPartId=-1|ShowNetName=T|Location.X=1030|Location.Y=940|Orientation=1|Color=128|FontID=1|Text=+3.3V_PCIE
|RECORD=17|IndexInSheet=36|OwnerPartId=-1|ShowNetName=T|Location.X=990|Location.Y=970|Orientation=1|Color=128|FontID=1|Text=+12V_PCIE
|RECORD=22|IndexInSheet=37|OwnerPartId=-1|Location.X=760|Location.Y=910|Color=255|Orientation=1|Symbol=Thin Cross|IsActive=T|SuppressAll=T
|RECORD=22|IndexInSheet=38|OwnerPartId=-1|Location.X=760|Location.Y=900|Color=255|Orientation=1|Symbol=Thin Cross|IsActive=T|SuppressAll=T
|RECORD=22|IndexInSheet=39|OwnerPartId=-1|Location.X=760|Location.Y=850|Color=255|Orientation=1|Symbol=Thin Cross|IsActive=T|SuppressAll=T
|RECORD=17|IndexInSheet=40|OwnerPartId=-1|ShowNetName=T|Location.X=540|Location.Y=810|Orientation=2|Color=255|FontID=1|Text=PCIE_RX0_P|IsCrossSheetConnector=T
|RECORD=17|IndexInSheet=41|OwnerPartId=-1|ShowNetName=T|Location.X=540|Location.Y=800|Orientation=2|Color=255|FontID=1|Text=PCIE_RX0_N|IsCrossSheetConnector=T
|RECORD=17|IndexInSheet=42|OwnerPartId=-1|ShowNetName=T|Location.X=540|Location.Y=760|Orientation=2|Color=255|FontID=1|Text=PCIE_RX1_P|IsCrossSheetConnector=T
|RECORD=17|IndexInSheet=43|OwnerPartId=-1|ShowNetName=T|Location.X=540|Location.Y=750|Orientation=2|Color=255|FontID=1|Text=PCIE_RX1_N|IsCrossSheetConnector=T
|RECORD=17|IndexInSheet=44|OwnerPartId=-1|ShowNetName=T|Location.X=540|Location.Y=720|Orientation=2|Color=255|FontID=1|Text=PCIE_RX2_P|IsCrossSheetConnector=T
|RECORD=17|IndexInSheet=45|OwnerPartId=-1|ShowNetName=T|Location.X=540|Location.Y=710|Orientation=2|Color=255|FontID=1|Text=PCIE_RX2_N|IsCrossSheetConnector=T
|RECORD=17|IndexInSheet=46|OwnerPartId=-1|ShowNetName=T|Location.X=540|Location.Y=680|Orientation=2|Color=255|FontID=1|Text=PCIE_RX3_P|IsCrossSheetConnector=T
|RECORD=17|IndexInSheet=47|OwnerPartId=-1|ShowNetName=T|Location.X=540|Location.Y=670|Orientation=2|Color=255|FontID=1|Text=PCIE_RX3_N|IsCrossSheetConnector=T
|RECORD=17|IndexInSheet=48|OwnerPartId=-1|ShowNetName=T|Location.X=1190|Location.Y=850|Color=255|FontID=1|Text=PCIE_PERST|IsCrossSheetConnector=T
|RECORD=17|IndexInSheet=49|OwnerPartId=-1|ShowNetName=T|Location.X=1190|Location.Y=820|Color=255|FontID=1|Text=PCIE_CLK_P|IsCrossSheetConnector=T
|RECORD=17|IndexInSheet=50|OwnerPartId=-1|ShowNetName=T|Location.X=1190|Location.Y=810|Color=255|FontID=1|Text=PCIE_CLK_N|IsCrossSheetConnector=T
|RECORD=17|IndexInSheet=51|OwnerPartId=-1|ShowNetName=T|Location.X=1190|Location.Y=790|Color=255|FontID=1|Text=PCIE_TX0_P|IsCrossSheetConnector=T
|RECORD=17|IndexInSheet=52|OwnerPartId=-1|ShowNetName=T|Location.X=1190|Location.Y=780|Color=255|FontID=1|Text=PCIE_TX0_N|IsCrossSheetConnector=T
|RECORD=17|IndexInSheet=53|OwnerPartId=-1|ShowNetName=T|Location.X=1190|Location.Y=740|Color=255|FontID=1|Text=PCIE_TX1_P|IsCrossSheetConnector=T
|RECORD=17|IndexInSheet=54|OwnerPartId=-1|ShowNetName=T|Location.X=1190|Location.Y=730|Color=255|FontID=1|Text=PCIE_TX1_N|IsCrossSheetConnector=T
|RECORD=17|IndexInSheet=55|OwnerPartId=-1|ShowNetName=T|Location.X=1190|Location.Y=700|Color=255|FontID=1|Text=PCIE_TX2_P|IsCrossSheetConnector=T
|RECORD=17|IndexInSheet=56|OwnerPartId=-1|ShowNetName=T|Location.X=1190|Location.Y=690|Color=255|FontID=1|Text=PCIE_TX2_N|IsCrossSheetConnector=T
|RECORD=17|IndexInSheet=57|OwnerPartId=-1|ShowNetName=T|Location.X=1190|Location.Y=660|Color=255|FontID=1|Text=PCIE_TX3_P|IsCrossSheetConnector=T
|RECORD=17|IndexInSheet=58|OwnerPartId=-1|ShowNetName=T|Location.X=1190|Location.Y=650|Color=255|FontID=1|Text=PCIE_TX3_N|IsCrossSheetConnector=T
|RECORD=4|IndexInSheet=59|OwnerPartId=-1|Location.X=800|Location.Y=1010|Color=8388608|FontID=4|Text=PCIe Connector
|RECORD=1|LibReference=RES_0603_4.7K|ComponentDescription=RES, 4.7K, 1%, 1/10W, TF, 0603|PartCount=2|DisplayModeCount=1|IndexInSheet=60|OwnerPartId=-1|Location.X=1060|Location.Y=860|Orientation=1|CurrentPartId=1|LibraryPath=*|SourceLibraryName=Resistors.IntLib|TargetFileName=*|AreaColor=11599871|Color=128|PartIDLocked=F|DesignItemId=RES_0603_4.7K|AllPinCount=2
|RECORD=41|OwnerIndex=71|OwnerPartId=-1|Location.X=1056|Location.Y=912|Color=8388608|FontID=2|IsHidden=T|Text=7/25/2013|Name=ModifyDate
|RECORD=41|OwnerIndex=71|IndexInSheet=1|OwnerPartId=-1|Location.X=1056|Location.Y=912|Color=8388608|FontID=2|IsHidden=T|Text=ERJ-3EKF4701V|Name=MFG PART NUM
|RECORD=41|OwnerIndex=71|IndexInSheet=2|OwnerPartId=-1|Location.X=1056|Location.Y=912|Color=8388608|FontID=2|IsHidden=T|Text=PANASONIC|Name=MFG NAME
|RECORD=41|OwnerIndex=71|IndexInSheet=3|OwnerPartId=-1|Location.X=1056|Location.Y=912|Color=8388608|FontID=2|IsHidden=T|Text=RES|Name=CATEGORY
|RECORD=41|OwnerIndex=71|IndexInSheet=4|OwnerPartId=-1|Location.X=1056|Location.Y=912|Color=8388608|FontID=2|IsHidden=T|Text=7/26/2013|Name=Date
|RECORD=41|OwnerIndex=71|IndexInSheet=5|OwnerPartId=-1|Location.X=1056|Location.Y=912|Color=8388608|FontID=2|IsHidden=T|Text=1%|Name=P1
|RECORD=41|OwnerIndex=71|IndexInSheet=6|OwnerPartId=-1|Location.X=1056|Location.Y=912|Color=8388608|FontID=2|IsHidden=T|Text=TF|Name=P3
|RECORD=41|OwnerIndex=71|IndexInSheet=7|OwnerPartId=-1|Location.X=1056|Location.Y=912|Color=8388608|FontID=2|IsHidden=T|Text=1/10W|Name=P2
|RECORD=41|OwnerIndex=71|IndexInSheet=8|OwnerPartId=-1|Location.X=1056|Location.Y=912|Color=8388608|FontID=2|IsHidden=T|Text=125C|Name=MAXTEMP
|RECORD=41|OwnerIndex=71|IndexInSheet=9|OwnerPartId=-1|Location.X=1056|Location.Y=912|Color=8388608|FontID=2|IsHidden=T|Text=-55C|Name=MINTEMP
|RECORD=41|OwnerIndex=71|IndexInSheet=10|OwnerPartId=-1|Location.X=1056|Location.Y=912|Color=8388608|FontID=2|IsHidden=T|Text=100PPM|Name=OTHER
|RECORD=41|OwnerIndex=71|IndexInSheet=11|OwnerPartId=-1|Location.X=1056|Location.Y=912|Color=8388608|FontID=2|IsHidden=T|Text=0603|Name=SIZE
|RECORD=41|OwnerIndex=71|IndexInSheet=12|OwnerPartId=-1|Location.X=1056|Location.Y=912|Color=8388608|FontID=2|IsHidden=T|Text=GENERIC|Name=SUB
|RECORD=41|OwnerIndex=71|IndexInSheet=13|OwnerPartId=-1|Location.X=1056|Location.Y=912|Color=8388608|FontID=2|IsHidden=T|Text=Digi-Key|Name=Supplier 1|ReadOnlyState=3
|RECORD=41|OwnerIndex=71|IndexInSheet=14|OwnerPartId=-1|Location.X=1056|Location.Y=912|Color=8388608|FontID=2|IsHidden=T|Text=P4.70KHCT-ND|Name=Supplier Part Number 1|ReadOnlyState=3
|RECORD=41|OwnerIndex=71|IndexInSheet=15|OwnerPartId=-1|Location.X=1056|Location.Y=912|Color=8388608|FontID=1|IsHidden=T|Text=*|Name=SHEETPART
|RECORD=41|OwnerIndex=71|IndexInSheet=16|OwnerPartId=-1|Location.X=1056|Location.Y=912|Color=8388608|FontID=1|IsHidden=T|Text=RES, 4.7K, 1%, 1/10W, TF, 0603|Name=DESC
|RECORD=41|OwnerIndex=71|IndexInSheet=17|OwnerPartId=-1|Location.X=1064|Location.Y=875|Color=8388608|FontID=2|Text=4.7K|Name=VALUE
|RECORD=2|OwnerIndex=71|OwnerPartId=1|FormalType=1|Electrical=4|PinConglomerate=35|PinLength=10|Location.X=1060|Location.Y=870|Name=1|Designator=1|PinPropagationDelay=0.000000E+000
|RECORD=2|OwnerIndex=71|OwnerPartId=1|FormalType=1|Electrical=4|PinConglomerate=33|PinLength=10|Location.X=1060|Location.Y=900|Name=2|Designator=2|PinPropagationDelay=0.000000E+000
|RECORD=6|OwnerIndex=71|IsNotAccesible=T|IndexInSheet=20|OwnerPartId=1|LineWidth=1|Color=16711680|LocationCount=7|X1=1060|Y1=900|X2=1057|Y2=897|X3=1063|Y3=891|X4=1057|Y4=885|X5=1063|Y5=879|X6=1057|Y6=873|X7=1060|Y7=870
|RECORD=41|OwnerIndex=71|IndexInSheet=21|OwnerPartId=-1|Location.X=1056|Location.Y=912|Color=8388608|FontID=1|IsHidden=T|Text=<VELENTIUM>|Name=VELENTIUM PART NUM
|RECORD=34|OwnerIndex=71|IndexInSheet=-1|OwnerPartId=-1|Location.X=1064|Location.Y=887|Color=8388608|FontID=3|Text=R22|Name=Designator|ReadOnlyState=1
|RECORD=41|OwnerIndex=71|IndexInSheet=-1|OwnerPartId=-1|Location.X=1056|Location.Y=912|Color=8388608|FontID=2|IsHidden=T|Text==MFG PART NUM|Name=Comment
|RECORD=44|OwnerIndex=71
|RECORD=45|OwnerIndex=98|IndexInSheet=-1|Description=Chip Resistor, 0603, 2-Leads, Body 1.57x0.85mm, IPC Medium Density|UseComponentLibrary=T|ModelName=RESC1608X50N|ModelType=PCBLIB|DatafileCount=1|ModelDatafileEntity0=RESC1608X50N|ModelDatafileKind0=PCBLib|IsCurrent=T|DatalinksLocked=T|DatabaseDatalinksLocked=T|IntegratedModel=T|DatabaseModel=T
|RECORD=46|OwnerIndex=99
|RECORD=48|OwnerIndex=99
|RECORD=1|LibReference=CAP_0402_0.1UF_50V|ComponentDescription=CAP, CER, 0.1UF, 50V, 10%, X7R, AEC-Q200, 0402|PartCount=2|DisplayModeCount=1|IndexInSheet=61|OwnerPartId=-1|Location.X=1130|Location.Y=630|Orientation=1|CurrentPartId=1|LibraryPath=*|SourceLibraryName=Capacitors.IntLib|TargetFileName=*|AreaColor=11599871|Color=128|PartIDLocked=F|DesignItemId=CAP_0402_0.1UF_50V|AllPinCount=2
|RECORD=41|OwnerIndex=102|OwnerPartId=-1|Location.X=1078|Location.Y=656|Color=8388608|FontID=2|IsHidden=T|Text=CAP, CER|Name=CATEGORY
|RECORD=41|OwnerIndex=102|IndexInSheet=1|OwnerPartId=-1|Location.X=1078|Location.Y=656|Color=8388608|FontID=2|IsHidden=T|Text=TDK|Name=MFG NAME
|RECORD=41|OwnerIndex=102|IndexInSheet=2|OwnerPartId=-1|Location.X=1078|Location.Y=656|Color=8388608|FontID=2|IsHidden=T|Text=CGA2B3X7R1H104K050BB|Name=MFG PART NUM
|RECORD=41|OwnerIndex=102|IndexInSheet=3|OwnerPartId=-1|Location.X=1078|Location.Y=656|Color=8388608|FontID=2|IsHidden=T|Text=10/23/2013|Name=MODIFY DATE
|RECORD=41|OwnerIndex=102|IndexInSheet=4|OwnerPartId=-1|Location.X=1078|Location.Y=656|Color=8388608|FontID=2|IsHidden=T|Name=Date
|RECORD=41|OwnerIndex=102|IndexInSheet=5|OwnerPartId=-1|Location.X=1078|Location.Y=656|Color=8388608|FontID=2|IsHidden=T|Text=*|Name=SHEETPART
|RECORD=41|OwnerIndex=102|IndexInSheet=6|OwnerPartId=-1|Location.X=1078|Location.Y=656|Color=8388608|FontID=2|IsHidden=T|Text=10%|Name=P1
|RECORD=41|OwnerIndex=102|IndexInSheet=7|OwnerPartId=-1|Location.X=1078|Location.Y=656|Color=8388608|FontID=2|IsHidden=T|Text=125C|Name=MAXTEMP
|RECORD=41|OwnerIndex=102|IndexInSheet=8|OwnerPartId=-1|Location.X=1078|Location.Y=656|Color=8388608|FontID=2|IsHidden=T|Text=-55C|Name=MINTEMP
|RECORD=41|OwnerIndex=102|IndexInSheet=9|OwnerPartId=-1|Location.X=1078|Location.Y=656|Color=8388608|FontID=2|IsHidden=T|Text=AEC-Q200|Name=OTHER
|RECORD=41|OwnerIndex=102|IndexInSheet=10|OwnerPartId=-1|Location.X=1078|Location.Y=656|Color=8388608|FontID=2|IsHidden=T|Text=50V|Name=P2
|RECORD=41|OwnerIndex=102|IndexInSheet=11|OwnerPartId=-1|Location.X=1078|Location.Y=656|Color=8388608|FontID=2|IsHidden=T|Text=X7R|Name=P3
|RECORD=41|OwnerIndex=102|IndexInSheet=12|OwnerPartId=-1|Location.X=1078|Location.Y=656|Color=8388608|FontID=2|IsHidden=T|Text=0402|Name=Size
|RECORD=41|OwnerIndex=102|IndexInSheet=13|OwnerPartId=-1|Location.X=1078|Location.Y=656|Color=8388608|FontID=2|IsHidden=T|Name=SUB
|RECORD=41|OwnerIndex=102|IndexInSheet=14|OwnerPartId=-1|Location.X=1078|Location.Y=656|Color=8388608|FontID=1|IsHidden=T|Text=CAP, CER, 0.1UF, 50V, 10%, X7R, AEC-Q200, 0402|Name=DESC
|RECORD=41|OwnerIndex=102|IndexInSheet=15|OwnerPartId=-1|Location.X=1078|Location.Y=656|Color=8388608|FontID=1|IsHidden=T|Text=Digi-Key|Name=Supplier 1|ReadOnlyState=3
|RECORD=41|OwnerIndex=102|IndexInSheet=16|OwnerPartId=-1|Location.X=1078|Location.Y=656|Color=8388608|FontID=1|IsHidden=T|Text=445-6899-1-ND|Name=Supplier Part Number 1|ReadOnlyState=3
|RECORD=41|OwnerIndex=102|IndexInSheet=17|OwnerPartId=-1|Location.X=1101|Location.Y=638|Color=8388608|FontID=2|Text=0.1UF|Name=VALUE
|RECORD=2|OwnerIndex=102|OwnerPartId=1|FormalType=1|Electrical=4|PinConglomerate=32|PinLength=10|Location.X=1100|Location.Y=650|Name=2|Designator=2|SwapIdPin=2|SwapIDPart=1|PinPropagationDelay=0.000000E+000
|RECORD=2|OwnerIndex=102|OwnerPartId=1|FormalType=1|Electrical=4|PinConglomerate=34|PinLength=10|Location.X=1090|Location.Y=650|Name=1|Designator=1|SwapIdPin=1|SwapIDPart=1|PinPropagationDelay=0.000000E+000
|RECORD=13|OwnerIndex=102|IsNotAccesible=T|IndexInSheet=20|OwnerPartId=1|Location.X=1097|Location.X_Frac=50000|Location.Y=650|Corner.X=1100|Corner.Y=650|LineWidth=1|Color=16711680
|RECORD=13|OwnerIndex=102|IsNotAccesible=T|IndexInSheet=21|OwnerPartId=1|Location.X=1090|Location.Y=650|Corner.X=1092|Corner.X_Frac=50000|Corner.Y=650|LineWidth=1|Color=16711680
|RECORD=13|OwnerIndex=102|IsNotAccesible=T|IndexInSheet=22|OwnerPartId=1|Location.X=1097|Location.X_Frac=50000|Location.Y=655|Corner.X=1097|Corner.X_Frac=50000|Corner.Y=645|LineWidth=1|Color=16711680
|RECORD=13|OwnerIndex=102|IsNotAccesible=T|IndexInSheet=23|OwnerPartId=1|Location.X=1092|Location.X_Frac=50000|Location.Y=655|Corner.X=1092|Corner.X_Frac=50000|Corner.Y=645|LineWidth=1|Color=16711680
|RECORD=41|OwnerIndex=102|IndexInSheet=24|OwnerPartId=-1|Location.X=1078|Location.Y=656|Color=8388608|FontID=1|IsHidden=T|Text=<VALENTIUM>|Name=VALENTIUM PART NUM
|RECORD=34|OwnerIndex=102|IndexInSheet=-1|OwnerPartId=-1|Location.X=1070|Location.Y=636|Color=8388608|FontID=3|Text=C53|Name=Designator|ReadOnlyState=1
|RECORD=41|OwnerIndex=102|IndexInSheet=-1|OwnerPartId=-1|Location.X=1078|Location.Y=656|Color=8388608|FontID=2|IsHidden=T|Text=CAP_0402_0.1UF_50V|Name=Comment|ReadOnlyState=1
|RECORD=44|OwnerIndex=102
|RECORD=45|OwnerIndex=132|IndexInSheet=-1|Description=Chip Capacitor, 0402, 2-Leads, Body 1.00x0.50mm, IPC Medium Density|UseComponentLibrary=T|ModelName=CAPC1005X06N|ModelType=PCBLIB|DatafileCount=1|ModelDatafileEntity0=CAPC1005X06N|ModelDatafileKind0=PCBLib|IsCurrent=T|DatalinksLocked=T|DatabaseDatalinksLocked=T|IntegratedModel=T|DatabaseModel=T
|RECORD=46|OwnerIndex=133
|RECORD=48|OwnerIndex=133
|RECORD=1|LibReference=CAP_0402_0.1UF_50V|ComponentDescription=CAP, CER, 0.1UF, 50V, 10%, X7R, AEC-Q200, 0402|PartCount=2|DisplayModeCount=1|IndexInSheet=62|OwnerPartId=-1|Location.X=1090|Location.Y=640|Orientation=1|CurrentPartId=1|LibraryPath=*|SourceLibraryName=Capacitors.IntLib|TargetFileName=*|AreaColor=11599871|Color=128|PartIDLocked=F|DesignItemId=CAP_0402_0.1UF_50V|AllPinCount=2
|RECORD=41|OwnerIndex=136|OwnerPartId=-1|Location.X=1038|Location.Y=666|Color=8388608|FontID=2|IsHidden=T|Text=CAP, CER|Name=CATEGORY
|RECORD=41|OwnerIndex=136|IndexInSheet=1|OwnerPartId=-1|Location.X=1038|Location.Y=666|Color=8388608|FontID=2|IsHidden=T|Text=TDK|Name=MFG NAME
|RECORD=41|OwnerIndex=136|IndexInSheet=2|OwnerPartId=-1|Location.X=1038|Location.Y=666|Color=8388608|FontID=2|IsHidden=T|Text=CGA2B3X7R1H104K050BB|Name=MFG PART NUM
|RECORD=41|OwnerIndex=136|IndexInSheet=3|OwnerPartId=-1|Location.X=1038|Location.Y=666|Color=8388608|FontID=2|IsHidden=T|Text=10/23/2013|Name=MODIFY DATE
|RECORD=41|OwnerIndex=136|IndexInSheet=4|OwnerPartId=-1|Location.X=1038|Location.Y=666|Color=8388608|FontID=2|IsHidden=T|Name=Date
|RECORD=41|OwnerIndex=136|IndexInSheet=5|OwnerPartId=-1|Location.X=1038|Location.Y=666|Color=8388608|FontID=2|IsHidden=T|Text=*|Name=SHEETPART
|RECORD=41|OwnerIndex=136|IndexInSheet=6|OwnerPartId=-1|Location.X=1038|Location.Y=666|Color=8388608|FontID=2|IsHidden=T|Text=10%|Name=P1
|RECORD=41|OwnerIndex=136|IndexInSheet=7|OwnerPartId=-1|Location.X=1038|Location.Y=666|Color=8388608|FontID=2|IsHidden=T|Text=125C|Name=MAXTEMP
|RECORD=41|OwnerIndex=136|IndexInSheet=8|OwnerPartId=-1|Location.X=1038|Location.Y=666|Color=8388608|FontID=2|IsHidden=T|Text=-55C|Name=MINTEMP
|RECORD=41|OwnerIndex=136|IndexInSheet=9|OwnerPartId=-1|Location.X=1038|Location.Y=666|Color=8388608|FontID=2|IsHidden=T|Text=AEC-Q200|Name=OTHER
|RECORD=41|OwnerIndex=136|IndexInSheet=10|OwnerPartId=-1|Location.X=1038|Location.Y=666|Color=8388608|FontID=2|IsHidden=T|Text=50V|Name=P2
|RECORD=41|OwnerIndex=136|IndexInSheet=11|OwnerPartId=-1|Location.X=1038|Location.Y=666|Color=8388608|FontID=2|IsHidden=T|Text=X7R|Name=P3
|RECORD=41|OwnerIndex=136|IndexInSheet=12|OwnerPartId=-1|Location.X=1038|Location.Y=666|Color=8388608|FontID=2|IsHidden=T|Text=0402|Name=Size
|RECORD=41|OwnerIndex=136|IndexInSheet=13|OwnerPartId=-1|Location.X=1038|Location.Y=666|Color=8388608|FontID=2|IsHidden=T|Name=SUB
|RECORD=41|OwnerIndex=136|IndexInSheet=14|OwnerPartId=-1|Location.X=1038|Location.Y=666|Color=8388608|FontID=1|IsHidden=T|Text=CAP, CER, 0.1UF, 50V, 10%, X7R, AEC-Q200, 0402|Name=DESC
|RECORD=41|OwnerIndex=136|IndexInSheet=15|OwnerPartId=-1|Location.X=1038|Location.Y=666|Color=8388608|FontID=1|IsHidden=T|Text=Digi-Key|Name=Supplier 1|ReadOnlyState=3
|RECORD=41|OwnerIndex=136|IndexInSheet=16|OwnerPartId=-1|Location.X=1038|Location.Y=666|Color=8388608|FontID=1|IsHidden=T|Text=445-6899-1-ND|Name=Supplier Part Number 1|ReadOnlyState=3
|RECORD=41|OwnerIndex=136|IndexInSheet=17|OwnerPartId=-1|Location.X=1060|Location.Y=660|Color=8388608|FontID=2|Text=0.1UF|Name=VALUE
|RECORD=2|OwnerIndex=136|OwnerPartId=1|FormalType=1|Electrical=4|PinConglomerate=32|PinLength=10|Location.X=1060|Location.Y=660|Name=2|Designator=2|SwapIdPin=2|SwapIDPart=1|PinPropagationDelay=0.000000E+000
|RECORD=2|OwnerIndex=136|OwnerPartId=1|FormalType=1|Electrical=4|PinConglomerate=34|PinLength=10|Location.X=1050|Location.Y=660|Name=1|Designator=1|SwapIdPin=1|SwapIDPart=1|PinPropagationDelay=0.000000E+000
|RECORD=13|OwnerIndex=136|IsNotAccesible=T|IndexInSheet=20|OwnerPartId=1|Location.X=1057|Location.X_Frac=50000|Location.Y=660|Corner.X=1060|Corner.Y=660|LineWidth=1|Color=16711680
|RECORD=13|OwnerIndex=136|IsNotAccesible=T|IndexInSheet=21|OwnerPartId=1|Location.X=1050|Location.Y=660|Corner.X=1052|Corner.X_Frac=50000|Corner.Y=660|LineWidth=1|Color=16711680
|RECORD=13|OwnerIndex=136|IsNotAccesible=T|IndexInSheet=22|OwnerPartId=1|Location.X=1057|Location.X_Frac=50000|Location.Y=665|Corner.X=1057|Corner.X_Frac=50000|Corner.Y=655|LineWidth=1|Color=16711680
|RECORD=13|OwnerIndex=136|IsNotAccesible=T|IndexInSheet=23|OwnerPartId=1|Location.X=1052|Location.X_Frac=50000|Location.Y=665|Corner.X=1052|Corner.X_Frac=50000|Corner.Y=655|LineWidth=1|Color=16711680
|RECORD=41|OwnerIndex=136|IndexInSheet=24|OwnerPartId=-1|Location.X=1038|Location.Y=666|Color=8388608|FontID=1|IsHidden=T|Text=<VALENTIUM>|Name=VALENTIUM PART NUM
|RECORD=34|OwnerIndex=136|IndexInSheet=-1|OwnerPartId=-1|Location.X=1030|Location.Y=660|Color=8388608|FontID=3|Text=C52|Name=Designator|ReadOnlyState=1
|RECORD=41|OwnerIndex=136|IndexInSheet=-1|OwnerPartId=-1|Location.X=1038|Location.Y=666|Color=8388608|FontID=2|IsHidden=T|Text=CAP_0402_0.1UF_50V|Name=Comment|ReadOnlyState=1
|RECORD=44|OwnerIndex=136
|RECORD=45|OwnerIndex=166|IndexInSheet=-1|Description=Chip Capacitor, 0402, 2-Leads, Body 1.00x0.50mm, IPC Medium Density|UseComponentLibrary=T|ModelName=CAPC1005X06N|ModelType=PCBLIB|DatafileCount=1|ModelDatafileEntity0=CAPC1005X06N|ModelDatafileKind0=PCBLib|IsCurrent=T|DatalinksLocked=T|DatabaseDatalinksLocked=T|IntegratedModel=T|DatabaseModel=T
|RECORD=46|OwnerIndex=167
|RECORD=48|OwnerIndex=167
|RECORD=1|LibReference=RES_0402_0|ComponentDescription=RES, 0. OHM, 1%, 1/16W, TF, AEC-Q200, 0402|PartCount=2|DisplayModeCount=1|IndexInSheet=63|OwnerPartId=-1|Location.X=670|Location.Y=640|CurrentPartId=1|LibraryPath=*|SourceLibraryName=Resistors.IntLib|TargetFileName=*|AreaColor=11599871|Color=128|PartIDLocked=F|DesignItemId=RES_0402_0|AllPinCount=2
|RECORD=41|OwnerIndex=170|OwnerPartId=-1|Location.X=670|Location.Y=640|Color=8388608|FontID=2|IsHidden=T|Text=7/25/2013|Name=ModifyDate
|RECORD=41|OwnerIndex=170|IndexInSheet=1|OwnerPartId=-1|Location.X=670|Location.Y=640|Color=8388608|FontID=2|IsHidden=T|Text=ERJ-2GE0R00X|Name=MFG PART NUM
|RECORD=41|OwnerIndex=170|IndexInSheet=2|OwnerPartId=-1|Location.X=670|Location.Y=640|Color=8388608|FontID=2|IsHidden=T|Text=PANASONIC|Name=MFG NAME
|RECORD=41|OwnerIndex=170|IndexInSheet=3|OwnerPartId=-1|Location.X=670|Location.Y=640|Color=8388608|FontID=2|IsHidden=T|Text=RES|Name=CATEGORY
|RECORD=41|OwnerIndex=170|IndexInSheet=4|OwnerPartId=-1|Location.X=668|Location.Y=650|Color=8388608|FontID=2|IsHidden=T|Text=7/26/2013|Name=Date
|RECORD=41|OwnerIndex=170|IndexInSheet=5|OwnerPartId=-1|Location.X=660|Location.X_Frac=55769|Location.Y=650|Color=8388608|FontID=2|IsHidden=T|Text=1%|Name=P1
|RECORD=41|OwnerIndex=170|IndexInSheet=6|OwnerPartId=-1|Location.X=660|Location.X_Frac=55769|Location.Y=650|Color=8388608|FontID=2|IsHidden=T|Text=TF|Name=P3
|RECORD=41|OwnerIndex=170|IndexInSheet=7|OwnerPartId=-1|Location.X=660|Location.X_Frac=55769|Location.Y=650|Color=8388608|FontID=2|IsHidden=T|Text=1/16W|Name=P2
|RECORD=41|OwnerIndex=170|IndexInSheet=8|OwnerPartId=-1|Location.X=660|Location.X_Frac=55769|Location.Y=650|Color=8388608|FontID=2|IsHidden=T|Text=155C|Name=MAXTEMP
|RECORD=41|OwnerIndex=170|IndexInSheet=9|OwnerPartId=-1|Location.X=660|Location.X_Frac=55769|Location.Y=650|Color=8388608|FontID=2|IsHidden=T|Text=-55C|Name=MINTEMP
|RECORD=41|OwnerIndex=170|IndexInSheet=10|OwnerPartId=-1|Location.X=660|Location.X_Frac=55769|Location.Y=650|Color=8388608|FontID=2|IsHidden=T|Text=100PPM, AEC-Q200|Name=OTHER
|RECORD=41|OwnerIndex=170|IndexInSheet=11|OwnerPartId=-1|Location.X=660|Location.X_Frac=55769|Location.Y=650|Color=8388608|FontID=2|IsHidden=T|Text=0402|Name=SIZE
|RECORD=41|OwnerIndex=170|IndexInSheet=12|OwnerPartId=-1|Location.X=660|Location.X_Frac=55769|Location.Y=650|Color=8388608|FontID=2|IsHidden=T|Text=GENERIC|Name=SUB
|RECORD=41|OwnerIndex=170|IndexInSheet=13|OwnerPartId=-1|Location.X=655|Location.X_Frac=98077|Location.Y=626|Color=8388608|FontID=1|IsHidden=T|Text=*|Name=SHEETPART
|RECORD=41|OwnerIndex=170|IndexInSheet=14|OwnerPartId=-1|Location.X=655|Location.X_Frac=98077|Location.Y=654|Color=8388608|FontID=1|IsHidden=T|Text=RES, 0 OHM, 1%, 1/16W, TF, AEC-Q200, 0402|Name=DESC
|RECORD=41|OwnerIndex=170|IndexInSheet=15|OwnerPartId=-1|Location.X=656|Location.X_Frac=60577|Location.Y=654|Color=8388608|FontID=1|IsHidden=T|Text=Digi-Key|Name=Supplier 1|ReadOnlyState=3
|RECORD=41|OwnerIndex=170|IndexInSheet=16|OwnerPartId=-1|Location.X=656|Location.X_Frac=60577|Location.Y=654|Color=8388608|FontID=1|IsHidden=T|Text=P0.0JCT-ND|Name=Supplier Part Number 1|ReadOnlyState=3
|RECORD=41|OwnerIndex=170|IndexInSheet=17|OwnerPartId=-1|Location.X=656|Location.X_Frac=61102|Location.Y=654|Color=8388608|FontID=1|IsHidden=T|Text=<VELENTIUM>|Name=VELENTIUM PART NUM
|RECORD=41|OwnerIndex=170|IndexInSheet=18|OwnerPartId=-1|Location.X=679|Location.Y=624|Color=8388608|FontID=2|Text=0 OHM|Name=VALUE
|RECORD=2|OwnerIndex=170|OwnerPartId=1|FormalType=1|Electrical=4|PinConglomerate=34|PinLength=10|Location.X=680|Location.Y=640|Name=1|Designator=1|PinPropagationDelay=0.000000E+000
|RECORD=2|OwnerIndex=170|OwnerPartId=1|FormalType=1|Electrical=4|PinConglomerate=32|PinLength=10|Location.X=710|Location.Y=640|Name=2|Designator=2|PinPropagationDelay=0.000000E+000
|RECORD=6|OwnerIndex=170|IsNotAccesible=T|IndexInSheet=21|OwnerPartId=1|LineWidth=1|Color=16711680|LocationCount=7|X1=710|Y1=640|X2=707|Y2=643|X3=701|Y3=637|X4=695|Y4=643|X5=689|Y5=637|X6=683|Y6=643|X7=680|Y7=640
|RECORD=34|OwnerIndex=170|IndexInSheet=-1|OwnerPartId=-1|Location.X=679|Location.Y=644|Color=8388608|FontID=3|Text=R24|Name=Designator|ReadOnlyState=1
|RECORD=41|OwnerIndex=170|IndexInSheet=-1|OwnerPartId=-1|Location.X=690|Location.Y=630|Color=8388608|FontID=2|IsHidden=T|Text=="MFG PART NUM"|Name=Comment
|RECORD=44|OwnerIndex=170
|RECORD=45|OwnerIndex=197|IndexInSheet=-1|Description=Chip Resistor, 0402, 2-Leads, Body 1.00x0.50mm, IPC Medium Density|UseComponentLibrary=T|ModelName=RESC1005X04N|ModelType=PCBLIB|DatafileCount=1|ModelDatafileEntity0=RESC1005X04N|ModelDatafileKind0=PCBLib|IsCurrent=T|DatalinksLocked=T|DatabaseDatalinksLocked=T|IntegratedModel=T|DatabaseModel=T
|RECORD=46|OwnerIndex=198
|RECORD=48|OwnerIndex=198
|RECORD=1|LibReference=RES_0402_0|ComponentDescription=RES, 0. OHM, 1%, 1/16W, TF, AEC-Q200, 0402|PartCount=2|DisplayModeCount=1|IndexInSheet=64|OwnerPartId=-1|Location.X=670|Location.Y=780|CurrentPartId=1|LibraryPath=*|SourceLibraryName=Resistors.IntLib|TargetFileName=*|AreaColor=11599871|Color=128|PartIDLocked=F|DesignItemId=RES_0402_0|AllPinCount=2
|RECORD=41|OwnerIndex=201|OwnerPartId=-1|Location.X=670|Location.Y=780|Color=8388608|FontID=2|IsHidden=T|Text=7/25/2013|Name=ModifyDate
|RECORD=41|OwnerIndex=201|IndexInSheet=1|OwnerPartId=-1|Location.X=670|Location.Y=780|Color=8388608|FontID=2|IsHidden=T|Text=ERJ-2GE0R00X|Name=MFG PART NUM
|RECORD=41|OwnerIndex=201|IndexInSheet=2|OwnerPartId=-1|Location.X=670|Location.Y=780|Color=8388608|FontID=2|IsHidden=T|Text=PANASONIC|Name=MFG NAME
|RECORD=41|OwnerIndex=201|IndexInSheet=3|OwnerPartId=-1|Location.X=670|Location.Y=780|Color=8388608|FontID=2|IsHidden=T|Text=RES|Name=CATEGORY
|RECORD=41|OwnerIndex=201|IndexInSheet=4|OwnerPartId=-1|Location.X=668|Location.Y=790|Color=8388608|FontID=2|IsHidden=T|Text=7/26/2013|Name=Date
|RECORD=41|OwnerIndex=201|IndexInSheet=5|OwnerPartId=-1|Location.X=660|Location.X_Frac=55769|Location.Y=790|Color=8388608|FontID=2|IsHidden=T|Text=1%|Name=P1
|RECORD=41|OwnerIndex=201|IndexInSheet=6|OwnerPartId=-1|Location.X=660|Location.X_Frac=55769|Location.Y=790|Color=8388608|FontID=2|IsHidden=T|Text=TF|Name=P3
|RECORD=41|OwnerIndex=201|IndexInSheet=7|OwnerPartId=-1|Location.X=660|Location.X_Frac=55769|Location.Y=790|Color=8388608|FontID=2|IsHidden=T|Text=1/16W|Name=P2
|RECORD=41|OwnerIndex=201|IndexInSheet=8|OwnerPartId=-1|Location.X=660|Location.X_Frac=55769|Location.Y=790|Color=8388608|FontID=2|IsHidden=T|Text=155C|Name=MAXTEMP
|RECORD=41|OwnerIndex=201|IndexInSheet=9|OwnerPartId=-1|Location.X=660|Location.X_Frac=55769|Location.Y=790|Color=8388608|FontID=2|IsHidden=T|Text=-55C|Name=MINTEMP
|RECORD=41|OwnerIndex=201|IndexInSheet=10|OwnerPartId=-1|Location.X=660|Location.X_Frac=55769|Location.Y=790|Color=8388608|FontID=2|IsHidden=T|Text=100PPM, AEC-Q200|Name=OTHER
|RECORD=41|OwnerIndex=201|IndexInSheet=11|OwnerPartId=-1|Location.X=660|Location.X_Frac=55769|Location.Y=790|Color=8388608|FontID=2|IsHidden=T|Text=0402|Name=SIZE
|RECORD=41|OwnerIndex=201|IndexInSheet=12|OwnerPartId=-1|Location.X=660|Location.X_Frac=55769|Location.Y=790|Color=8388608|FontID=2|IsHidden=T|Text=GENERIC|Name=SUB
|RECORD=41|OwnerIndex=201|IndexInSheet=13|OwnerPartId=-1|Location.X=655|Location.X_Frac=98077|Location.Y=766|Color=8388608|FontID=1|IsHidden=T|Text=*|Name=SHEETPART
|RECORD=41|OwnerIndex=201|IndexInSheet=14|OwnerPartId=-1|Location.X=655|Location.X_Frac=98077|Location.Y=794|Color=8388608|FontID=1|IsHidden=T|Text=RES, 0 OHM, 1%, 1/16W, TF, AEC-Q200, 0402|Name=DESC
|RECORD=41|OwnerIndex=201|IndexInSheet=15|OwnerPartId=-1|Location.X=656|Location.X_Frac=60577|Location.Y=794|Color=8388608|FontID=1|IsHidden=T|Text=Digi-Key|Name=Supplier 1|ReadOnlyState=3
|RECORD=41|OwnerIndex=201|IndexInSheet=16|OwnerPartId=-1|Location.X=656|Location.X_Frac=60577|Location.Y=794|Color=8388608|FontID=1|IsHidden=T|Text=P0.0JCT-ND|Name=Supplier Part Number 1|ReadOnlyState=3
|RECORD=41|OwnerIndex=201|IndexInSheet=17|OwnerPartId=-1|Location.X=656|Location.X_Frac=61102|Location.Y=794|Color=8388608|FontID=1|IsHidden=T|Text=<VELENTIUM>|Name=VELENTIUM PART NUM
|RECORD=41|OwnerIndex=201|IndexInSheet=18|OwnerPartId=-1|Location.X=679|Location.Y=764|Color=8388608|FontID=2|Text=0 OHM|Name=VALUE
|RECORD=2|OwnerIndex=201|OwnerPartId=1|FormalType=1|Electrical=4|PinConglomerate=34|PinLength=10|Location.X=680|Location.Y=780|Name=1|Designator=1|PinPropagationDelay=0.000000E+000
|RECORD=2|OwnerIndex=201|OwnerPartId=1|FormalType=1|Electrical=4|PinConglomerate=32|PinLength=10|Location.X=710|Location.Y=780|Name=2|Designator=2|PinPropagationDelay=0.000000E+000
|RECORD=6|OwnerIndex=201|IsNotAccesible=T|IndexInSheet=21|OwnerPartId=1|LineWidth=1|Color=16711680|LocationCount=7|X1=710|Y1=780|X2=707|Y2=783|X3=701|Y3=777|X4=695|Y4=783|X5=689|Y5=777|X6=683|Y6=783|X7=680|Y7=780
|RECORD=34|OwnerIndex=201|IndexInSheet=-1|OwnerPartId=-1|Location.X=679|Location.Y=784|Color=8388608|FontID=3|Text=R23|Name=Designator|ReadOnlyState=1
|RECORD=41|OwnerIndex=201|IndexInSheet=-1|OwnerPartId=-1|Location.X=690|Location.Y=770|Color=8388608|FontID=2|IsHidden=T|Text=="MFG PART NUM"|Name=Comment
|RECORD=44|OwnerIndex=201
|RECORD=45|OwnerIndex=228|IndexInSheet=-1|Description=Chip Resistor, 0402, 2-Leads, Body 1.00x0.50mm, IPC Medium Density|UseComponentLibrary=T|ModelName=RESC1005X04N|ModelType=PCBLIB|DatafileCount=1|ModelDatafileEntity0=RESC1005X04N|ModelDatafileKind0=PCBLib|IsCurrent=T|DatalinksLocked=T|DatabaseDatalinksLocked=T|IntegratedModel=T|DatabaseModel=T
|RECORD=46|OwnerIndex=229
|RECORD=48|OwnerIndex=229
|RECORD=1|LibReference=CAP_0402_0.1UF_50V|ComponentDescription=CAP, CER, 0.1UF, 50V, 10%, X7R, AEC-Q200, 0402|PartCount=2|DisplayModeCount=1|IndexInSheet=65|OwnerPartId=-1|Location.X=1130|Location.Y=670|Orientation=1|CurrentPartId=1|LibraryPath=*|SourceLibraryName=Capacitors.IntLib|TargetFileName=*|AreaColor=11599871|Color=128|PartIDLocked=F|DesignItemId=CAP_0402_0.1UF_50V|AllPinCount=2
|RECORD=41|OwnerIndex=232|OwnerPartId=-1|Location.X=1078|Location.Y=696|Color=8388608|FontID=2|IsHidden=T|Text=CAP, CER|Name=CATEGORY
|RECORD=41|OwnerIndex=232|IndexInSheet=1|OwnerPartId=-1|Location.X=1078|Location.Y=696|Color=8388608|FontID=2|IsHidden=T|Text=TDK|Name=MFG NAME
|RECORD=41|OwnerIndex=232|IndexInSheet=2|OwnerPartId=-1|Location.X=1078|Location.Y=696|Color=8388608|FontID=2|IsHidden=T|Text=CGA2B3X7R1H104K050BB|Name=MFG PART NUM
|RECORD=41|OwnerIndex=232|IndexInSheet=3|OwnerPartId=-1|Location.X=1078|Location.Y=696|Color=8388608|FontID=2|IsHidden=T|Text=10/23/2013|Name=MODIFY DATE
|RECORD=41|OwnerIndex=232|IndexInSheet=4|OwnerPartId=-1|Location.X=1078|Location.Y=696|Color=8388608|FontID=2|IsHidden=T|Name=Date
|RECORD=41|OwnerIndex=232|IndexInSheet=5|OwnerPartId=-1|Location.X=1078|Location.Y=696|Color=8388608|FontID=2|IsHidden=T|Text=*|Name=SHEETPART
|RECORD=41|OwnerIndex=232|IndexInSheet=6|OwnerPartId=-1|Location.X=1078|Location.Y=696|Color=8388608|FontID=2|IsHidden=T|Text=10%|Name=P1
|RECORD=41|OwnerIndex=232|IndexInSheet=7|OwnerPartId=-1|Location.X=1078|Location.Y=696|Color=8388608|FontID=2|IsHidden=T|Text=125C|Name=MAXTEMP
|RECORD=41|OwnerIndex=232|IndexInSheet=8|OwnerPartId=-1|Location.X=1078|Location.Y=696|Color=8388608|FontID=2|IsHidden=T|Text=-55C|Name=MINTEMP
|RECORD=41|OwnerIndex=232|IndexInSheet=9|OwnerPartId=-1|Location.X=1078|Location.Y=696|Color=8388608|FontID=2|IsHidden=T|Text=AEC-Q200|Name=OTHER
|RECORD=41|OwnerIndex=232|IndexInSheet=10|OwnerPartId=-1|Location.X=1078|Location.Y=696|Color=8388608|FontID=2|IsHidden=T|Text=50V|Name=P2
|RECORD=41|OwnerIndex=232|IndexInSheet=11|OwnerPartId=-1|Location.X=1078|Location.Y=696|Color=8388608|FontID=2|IsHidden=T|Text=X7R|Name=P3
|RECORD=41|OwnerIndex=232|IndexInSheet=12|OwnerPartId=-1|Location.X=1078|Location.Y=696|Color=8388608|FontID=2|IsHidden=T|Text=0402|Name=Size
|RECORD=41|OwnerIndex=232|IndexInSheet=13|OwnerPartId=-1|Location.X=1078|Location.Y=696|Color=8388608|FontID=2|IsHidden=T|Name=SUB
|RECORD=41|OwnerIndex=232|IndexInSheet=14|OwnerPartId=-1|Location.X=1078|Location.Y=696|Color=8388608|FontID=1|IsHidden=T|Text=CAP, CER, 0.1UF, 50V, 10%, X7R, AEC-Q200, 0402|Name=DESC
|RECORD=41|OwnerIndex=232|IndexInSheet=15|OwnerPartId=-1|Location.X=1078|Location.Y=696|Color=8388608|FontID=1|IsHidden=T|Text=Digi-Key|Name=Supplier 1|ReadOnlyState=3
|RECORD=41|OwnerIndex=232|IndexInSheet=16|OwnerPartId=-1|Location.X=1078|Location.Y=696|Color=8388608|FontID=1|IsHidden=T|Text=445-6899-1-ND|Name=Supplier Part Number 1|ReadOnlyState=3
|RECORD=41|OwnerIndex=232|IndexInSheet=17|OwnerPartId=-1|Location.X=1101|Location.Y=678|Color=8388608|FontID=2|Text=0.1UF|Name=VALUE
|RECORD=2|OwnerIndex=232|OwnerPartId=1|FormalType=1|Electrical=4|PinConglomerate=32|PinLength=10|Location.X=1100|Location.Y=690|Name=2|Designator=2|SwapIdPin=2|SwapIDPart=1|PinPropagationDelay=0.000000E+000
|RECORD=2|OwnerIndex=232|OwnerPartId=1|FormalType=1|Electrical=4|PinConglomerate=34|PinLength=10|Location.X=1090|Location.Y=690|Name=1|Designator=1|SwapIdPin=1|SwapIDPart=1|PinPropagationDelay=0.000000E+000
|RECORD=13|OwnerIndex=232|IsNotAccesible=T|IndexInSheet=20|OwnerPartId=1|Location.X=1097|Location.X_Frac=50000|Location.Y=690|Corner.X=1100|Corner.Y=690|LineWidth=1|Color=16711680
|RECORD=13|OwnerIndex=232|IsNotAccesible=T|IndexInSheet=21|OwnerPartId=1|Location.X=1090|Location.Y=690|Corner.X=1092|Corner.X_Frac=50000|Corner.Y=690|LineWidth=1|Color=16711680
|RECORD=13|OwnerIndex=232|IsNotAccesible=T|IndexInSheet=22|OwnerPartId=1|Location.X=1097|Location.X_Frac=50000|Location.Y=695|Corner.X=1097|Corner.X_Frac=50000|Corner.Y=685|LineWidth=1|Color=16711680
|RECORD=13|OwnerIndex=232|IsNotAccesible=T|IndexInSheet=23|OwnerPartId=1|Location.X=1092|Location.X_Frac=50000|Location.Y=695|Corner.X=1092|Corner.X_Frac=50000|Corner.Y=685|LineWidth=1|Color=16711680
|RECORD=41|OwnerIndex=232|IndexInSheet=24|OwnerPartId=-1|Location.X=1078|Location.Y=696|Color=8388608|FontID=1|IsHidden=T|Text=<VALENTIUM>|Name=VALENTIUM PART NUM
|RECORD=34|OwnerIndex=232|IndexInSheet=-1|OwnerPartId=-1|Location.X=1070|Location.Y=676|Color=8388608|FontID=3|Text=C51|Name=Designator|ReadOnlyState=1
|RECORD=41|OwnerIndex=232|IndexInSheet=-1|OwnerPartId=-1|Location.X=1078|Location.Y=696|Color=8388608|FontID=2|IsHidden=T|Text=CAP_0402_0.1UF_50V|Name=Comment|ReadOnlyState=1
|RECORD=44|OwnerIndex=232
|RECORD=45|OwnerIndex=262|IndexInSheet=-1|Description=Chip Capacitor, 0402, 2-Leads, Body 1.00x0.50mm, IPC Medium Density|UseComponentLibrary=T|ModelName=CAPC1005X06N|ModelType=PCBLIB|DatafileCount=1|ModelDatafileEntity0=CAPC1005X06N|ModelDatafileKind0=PCBLib|IsCurrent=T|DatalinksLocked=T|DatabaseDatalinksLocked=T|IntegratedModel=T|DatabaseModel=T
|RECORD=46|OwnerIndex=263
|RECORD=48|OwnerIndex=263
|RECORD=1|LibReference=CAP_0402_0.1UF_50V|ComponentDescription=CAP, CER, 0.1UF, 50V, 10%, X7R, AEC-Q200, 0402|PartCount=2|DisplayModeCount=1|IndexInSheet=66|OwnerPartId=-1|Location.X=1130|Location.Y=710|Orientation=1|CurrentPartId=1|LibraryPath=*|SourceLibraryName=Capacitors.IntLib|TargetFileName=*|AreaColor=11599871|Color=128|PartIDLocked=F|DesignItemId=CAP_0402_0.1UF_50V|AllPinCount=2
|RECORD=41|OwnerIndex=266|OwnerPartId=-1|Location.X=1078|Location.Y=736|Color=8388608|FontID=2|IsHidden=T|Text=CAP, CER|Name=CATEGORY
|RECORD=41|OwnerIndex=266|IndexInSheet=1|OwnerPartId=-1|Location.X=1078|Location.Y=736|Color=8388608|FontID=2|IsHidden=T|Text=TDK|Name=MFG NAME
|RECORD=41|OwnerIndex=266|IndexInSheet=2|OwnerPartId=-1|Location.X=1078|Location.Y=736|Color=8388608|FontID=2|IsHidden=T|Text=CGA2B3X7R1H104K050BB|Name=MFG PART NUM
|RECORD=41|OwnerIndex=266|IndexInSheet=3|OwnerPartId=-1|Location.X=1078|Location.Y=736|Color=8388608|FontID=2|IsHidden=T|Text=10/23/2013|Name=MODIFY DATE
|RECORD=41|OwnerIndex=266|IndexInSheet=4|OwnerPartId=-1|Location.X=1078|Location.Y=736|Color=8388608|FontID=2|IsHidden=T|Name=Date
|RECORD=41|OwnerIndex=266|IndexInSheet=5|OwnerPartId=-1|Location.X=1078|Location.Y=736|Color=8388608|FontID=2|IsHidden=T|Text=*|Name=SHEETPART
|RECORD=41|OwnerIndex=266|IndexInSheet=6|OwnerPartId=-1|Location.X=1078|Location.Y=736|Color=8388608|FontID=2|IsHidden=T|Text=10%|Name=P1
|RECORD=41|OwnerIndex=266|IndexInSheet=7|OwnerPartId=-1|Location.X=1078|Location.Y=736|Color=8388608|FontID=2|IsHidden=T|Text=125C|Name=MAXTEMP
|RECORD=41|OwnerIndex=266|IndexInSheet=8|OwnerPartId=-1|Location.X=1078|Location.Y=736|Color=8388608|FontID=2|IsHidden=T|Text=-55C|Name=MINTEMP
|RECORD=41|OwnerIndex=266|IndexInSheet=9|OwnerPartId=-1|Location.X=1078|Location.Y=736|Color=8388608|FontID=2|IsHidden=T|Text=AEC-Q200|Name=OTHER
|RECORD=41|OwnerIndex=266|IndexInSheet=10|OwnerPartId=-1|Location.X=1078|Location.Y=736|Color=8388608|FontID=2|IsHidden=T|Text=50V|Name=P2
|RECORD=41|OwnerIndex=266|IndexInSheet=11|OwnerPartId=-1|Location.X=1078|Location.Y=736|Color=8388608|FontID=2|IsHidden=T|Text=X7R|Name=P3
|RECORD=41|OwnerIndex=266|IndexInSheet=12|OwnerPartId=-1|Location.X=1078|Location.Y=736|Color=8388608|FontID=2|IsHidden=T|Text=0402|Name=Size
|RECORD=41|OwnerIndex=266|IndexInSheet=13|OwnerPartId=-1|Location.X=1078|Location.Y=736|Color=8388608|FontID=2|IsHidden=T|Name=SUB
|RECORD=41|OwnerIndex=266|IndexInSheet=14|OwnerPartId=-1|Location.X=1078|Location.Y=736|Color=8388608|FontID=1|IsHidden=T|Text=CAP, CER, 0.1UF, 50V, 10%, X7R, AEC-Q200, 0402|Name=DESC
|RECORD=41|OwnerIndex=266|IndexInSheet=15|OwnerPartId=-1|Location.X=1078|Location.Y=736|Color=8388608|FontID=1|IsHidden=T|Text=Digi-Key|Name=Supplier 1|ReadOnlyState=3
|RECORD=41|OwnerIndex=266|IndexInSheet=16|OwnerPartId=-1|Location.X=1078|Location.Y=736|Color=8388608|FontID=1|IsHidden=T|Text=445-6899-1-ND|Name=Supplier Part Number 1|ReadOnlyState=3
|RECORD=41|OwnerIndex=266|IndexInSheet=17|OwnerPartId=-1|Location.X=1101|Location.Y=718|Color=8388608|FontID=2|Text=0.1UF|Name=VALUE
|RECORD=2|OwnerIndex=266|OwnerPartId=1|FormalType=1|Electrical=4|PinConglomerate=32|PinLength=10|Location.X=1100|Location.Y=730|Name=2|Designator=2|SwapIdPin=2|SwapIDPart=1|PinPropagationDelay=0.000000E+000
|RECORD=2|OwnerIndex=266|OwnerPartId=1|FormalType=1|Electrical=4|PinConglomerate=34|PinLength=10|Location.X=1090|Location.Y=730|Name=1|Designator=1|SwapIdPin=1|SwapIDPart=1|PinPropagationDelay=0.000000E+000
|RECORD=13|OwnerIndex=266|IsNotAccesible=T|IndexInSheet=20|OwnerPartId=1|Location.X=1097|Location.X_Frac=50000|Location.Y=730|Corner.X=1100|Corner.Y=730|LineWidth=1|Color=16711680
|RECORD=13|OwnerIndex=266|IsNotAccesible=T|IndexInSheet=21|OwnerPartId=1|Location.X=1090|Location.Y=730|Corner.X=1092|Corner.X_Frac=50000|Corner.Y=730|LineWidth=1|Color=16711680
|RECORD=13|OwnerIndex=266|IsNotAccesible=T|IndexInSheet=22|OwnerPartId=1|Location.X=1097|Location.X_Frac=50000|Location.Y=735|Corner.X=1097|Corner.X_Frac=50000|Corner.Y=725|LineWidth=1|Color=16711680
|RECORD=13|OwnerIndex=266|IsNotAccesible=T|IndexInSheet=23|OwnerPartId=1|Location.X=1092|Location.X_Frac=50000|Location.Y=735|Corner.X=1092|Corner.X_Frac=50000|Corner.Y=725|LineWidth=1|Color=16711680
|RECORD=41|OwnerIndex=266|IndexInSheet=24|OwnerPartId=-1|Location.X=1078|Location.Y=736|Color=8388608|FontID=1|IsHidden=T|Text=<VALENTIUM>|Name=VALENTIUM PART NUM
|RECORD=34|OwnerIndex=266|IndexInSheet=-1|OwnerPartId=-1|Location.X=1070|Location.Y=716|Color=8388608|FontID=3|Text=C49|Name=Designator|ReadOnlyState=1
|RECORD=41|OwnerIndex=266|IndexInSheet=-1|OwnerPartId=-1|Location.X=1078|Location.Y=736|Color=8388608|FontID=2|IsHidden=T|Text=CAP_0402_0.1UF_50V|Name=Comment|ReadOnlyState=1
|RECORD=44|OwnerIndex=266
|RECORD=45|OwnerIndex=296|IndexInSheet=-1|Description=Chip Capacitor, 0402, 2-Leads, Body 1.00x0.50mm, IPC Medium Density|UseComponentLibrary=T|ModelName=CAPC1005X06N|ModelType=PCBLIB|DatafileCount=1|ModelDatafileEntity0=CAPC1005X06N|ModelDatafileKind0=PCBLib|IsCurrent=T|DatalinksLocked=T|DatabaseDatalinksLocked=T|IntegratedModel=T|DatabaseModel=T
|RECORD=46|OwnerIndex=297
|RECORD=48|OwnerIndex=297
|RECORD=1|LibReference=CAP_0402_0.1UF_50V|ComponentDescription=CAP, CER, 0.1UF, 50V, 10%, X7R, AEC-Q200, 0402|PartCount=2|DisplayModeCount=1|IndexInSheet=67|OwnerPartId=-1|Location.X=1130|Location.Y=760|Orientation=1|CurrentPartId=1|LibraryPath=*|SourceLibraryName=Capacitors.IntLib|TargetFileName=*|AreaColor=11599871|Color=128|PartIDLocked=F|DesignItemId=CAP_0402_0.1UF_50V|AllPinCount=2
|RECORD=41|OwnerIndex=300|OwnerPartId=-1|Location.X=1078|Location.Y=786|Color=8388608|FontID=2|IsHidden=T|Text=CAP, CER|Name=CATEGORY
|RECORD=41|OwnerIndex=300|IndexInSheet=1|OwnerPartId=-1|Location.X=1078|Location.Y=786|Color=8388608|FontID=2|IsHidden=T|Text=TDK|Name=MFG NAME
|RECORD=41|OwnerIndex=300|IndexInSheet=2|OwnerPartId=-1|Location.X=1078|Location.Y=786|Color=8388608|FontID=2|IsHidden=T|Text=CGA2B3X7R1H104K050BB|Name=MFG PART NUM
|RECORD=41|OwnerIndex=300|IndexInSheet=3|OwnerPartId=-1|Location.X=1078|Location.Y=786|Color=8388608|FontID=2|IsHidden=T|Text=10/23/2013|Name=MODIFY DATE
|RECORD=41|OwnerIndex=300|IndexInSheet=4|OwnerPartId=-1|Location.X=1078|Location.Y=786|Color=8388608|FontID=2|IsHidden=T|Name=Date
|RECORD=41|OwnerIndex=300|IndexInSheet=5|OwnerPartId=-1|Location.X=1078|Location.Y=786|Color=8388608|FontID=2|IsHidden=T|Text=*|Name=SHEETPART
|RECORD=41|OwnerIndex=300|IndexInSheet=6|OwnerPartId=-1|Location.X=1078|Location.Y=786|Color=8388608|FontID=2|IsHidden=T|Text=10%|Name=P1
|RECORD=41|OwnerIndex=300|IndexInSheet=7|OwnerPartId=-1|Location.X=1078|Location.Y=786|Color=8388608|FontID=2|IsHidden=T|Text=125C|Name=MAXTEMP
|RECORD=41|OwnerIndex=300|IndexInSheet=8|OwnerPartId=-1|Location.X=1078|Location.Y=786|Color=8388608|FontID=2|IsHidden=T|Text=-55C|Name=MINTEMP
|RECORD=41|OwnerIndex=300|IndexInSheet=9|OwnerPartId=-1|Location.X=1078|Location.Y=786|Color=8388608|FontID=2|IsHidden=T|Text=AEC-Q200|Name=OTHER
|RECORD=41|OwnerIndex=300|IndexInSheet=10|OwnerPartId=-1|Location.X=1078|Location.Y=786|Color=8388608|FontID=2|IsHidden=T|Text=50V|Name=P2
|RECORD=41|OwnerIndex=300|IndexInSheet=11|OwnerPartId=-1|Location.X=1078|Location.Y=786|Color=8388608|FontID=2|IsHidden=T|Text=X7R|Name=P3
|RECORD=41|OwnerIndex=300|IndexInSheet=12|OwnerPartId=-1|Location.X=1078|Location.Y=786|Color=8388608|FontID=2|IsHidden=T|Text=0402|Name=Size
|RECORD=41|OwnerIndex=300|IndexInSheet=13|OwnerPartId=-1|Location.X=1078|Location.Y=786|Color=8388608|FontID=2|IsHidden=T|Name=SUB
|RECORD=41|OwnerIndex=300|IndexInSheet=14|OwnerPartId=-1|Location.X=1078|Location.Y=786|Color=8388608|FontID=1|IsHidden=T|Text=CAP, CER, 0.1UF, 50V, 10%, X7R, AEC-Q200, 0402|Name=DESC
|RECORD=41|OwnerIndex=300|IndexInSheet=15|OwnerPartId=-1|Location.X=1078|Location.Y=786|Color=8388608|FontID=1|IsHidden=T|Text=Digi-Key|Name=Supplier 1|ReadOnlyState=3
|RECORD=41|OwnerIndex=300|IndexInSheet=16|OwnerPartId=-1|Location.X=1078|Location.Y=786|Color=8388608|FontID=1|IsHidden=T|Text=445-6899-1-ND|Name=Supplier Part Number 1|ReadOnlyState=3
|RECORD=41|OwnerIndex=300|IndexInSheet=17|OwnerPartId=-1|Location.X=1101|Location.Y=768|Color=8388608|FontID=2|Text=0.1UF|Name=VALUE
|RECORD=2|OwnerIndex=300|OwnerPartId=1|FormalType=1|Electrical=4|PinConglomerate=32|PinLength=10|Location.X=1100|Location.Y=780|Name=2|Designator=2|SwapIdPin=2|SwapIDPart=1|PinPropagationDelay=0.000000E+000
|RECORD=2|OwnerIndex=300|OwnerPartId=1|FormalType=1|Electrical=4|PinConglomerate=34|PinLength=10|Location.X=1090|Location.Y=780|Name=1|Designator=1|SwapIdPin=1|SwapIDPart=1|PinPropagationDelay=0.000000E+000
|RECORD=13|OwnerIndex=300|IsNotAccesible=T|IndexInSheet=20|OwnerPartId=1|Location.X=1097|Location.X_Frac=50000|Location.Y=780|Corner.X=1100|Corner.Y=780|LineWidth=1|Color=16711680
|RECORD=13|OwnerIndex=300|IsNotAccesible=T|IndexInSheet=21|OwnerPartId=1|Location.X=1090|Location.Y=780|Corner.X=1092|Corner.X_Frac=50000|Corner.Y=780|LineWidth=1|Color=16711680
|RECORD=13|OwnerIndex=300|IsNotAccesible=T|IndexInSheet=22|OwnerPartId=1|Location.X=1097|Location.X_Frac=50000|Location.Y=785|Corner.X=1097|Corner.X_Frac=50000|Corner.Y=775|LineWidth=1|Color=16711680
|RECORD=13|OwnerIndex=300|IsNotAccesible=T|IndexInSheet=23|OwnerPartId=1|Location.X=1092|Location.X_Frac=50000|Location.Y=785|Corner.X=1092|Corner.X_Frac=50000|Corner.Y=775|LineWidth=1|Color=16711680
|RECORD=41|OwnerIndex=300|IndexInSheet=24|OwnerPartId=-1|Location.X=1078|Location.Y=786|Color=8388608|FontID=1|IsHidden=T|Text=<VALENTIUM>|Name=VALENTIUM PART NUM
|RECORD=34|OwnerIndex=300|IndexInSheet=-1|OwnerPartId=-1|Location.X=1070|Location.Y=766|Color=8388608|FontID=3|Text=C47|Name=Designator|ReadOnlyState=1
|RECORD=41|OwnerIndex=300|IndexInSheet=-1|OwnerPartId=-1|Location.X=1078|Location.Y=786|Color=8388608|FontID=2|IsHidden=T|Text=CAP_0402_0.1UF_50V|Name=Comment|ReadOnlyState=1
|RECORD=44|OwnerIndex=300
|RECORD=45|OwnerIndex=330|IndexInSheet=-1|Description=Chip Capacitor, 0402, 2-Leads, Body 1.00x0.50mm, IPC Medium Density|UseComponentLibrary=T|ModelName=CAPC1005X06N|ModelType=PCBLIB|DatafileCount=1|ModelDatafileEntity0=CAPC1005X06N|ModelDatafileKind0=PCBLib|IsCurrent=T|DatalinksLocked=T|DatabaseDatalinksLocked=T|IntegratedModel=T|DatabaseModel=T
|RECORD=46|OwnerIndex=331
|RECORD=48|OwnerIndex=331
|RECORD=1|LibReference=CAP_0402_0.1UF_50V|ComponentDescription=CAP, CER, 0.1UF, 50V, 10%, X7R, AEC-Q200, 0402|PartCount=2|DisplayModeCount=1|IndexInSheet=68|OwnerPartId=-1|Location.X=1130|Location.Y=790|Orientation=1|CurrentPartId=1|LibraryPath=*|SourceLibraryName=Capacitors.IntLib|TargetFileName=*|AreaColor=11599871|Color=128|PartIDLocked=F|DesignItemId=CAP_0402_0.1UF_50V|AllPinCount=2
|RECORD=41|OwnerIndex=334|OwnerPartId=-1|Location.X=1078|Location.Y=816|Color=8388608|FontID=2|IsHidden=T|Text=CAP, CER|Name=CATEGORY
|RECORD=41|OwnerIndex=334|IndexInSheet=1|OwnerPartId=-1|Location.X=1078|Location.Y=816|Color=8388608|FontID=2|IsHidden=T|Text=TDK|Name=MFG NAME
|RECORD=41|OwnerIndex=334|IndexInSheet=2|OwnerPartId=-1|Location.X=1078|Location.Y=816|Color=8388608|FontID=2|IsHidden=T|Text=CGA2B3X7R1H104K050BB|Name=MFG PART NUM
|RECORD=41|OwnerIndex=334|IndexInSheet=3|OwnerPartId=-1|Location.X=1078|Location.Y=816|Color=8388608|FontID=2|IsHidden=T|Text=10/23/2013|Name=MODIFY DATE
|RECORD=41|OwnerIndex=334|IndexInSheet=4|OwnerPartId=-1|Location.X=1078|Location.Y=816|Color=8388608|FontID=2|IsHidden=T|Name=Date
|RECORD=41|OwnerIndex=334|IndexInSheet=5|OwnerPartId=-1|Location.X=1078|Location.Y=816|Color=8388608|FontID=2|IsHidden=T|Text=*|Name=SHEETPART
|RECORD=41|OwnerIndex=334|IndexInSheet=6|OwnerPartId=-1|Location.X=1078|Location.Y=816|Color=8388608|FontID=2|IsHidden=T|Text=10%|Name=P1
|RECORD=41|OwnerIndex=334|IndexInSheet=7|OwnerPartId=-1|Location.X=1078|Location.Y=816|Color=8388608|FontID=2|IsHidden=T|Text=125C|Name=MAXTEMP
|RECORD=41|OwnerIndex=334|IndexInSheet=8|OwnerPartId=-1|Location.X=1078|Location.Y=816|Color=8388608|FontID=2|IsHidden=T|Text=-55C|Name=MINTEMP
|RECORD=41|OwnerIndex=334|IndexInSheet=9|OwnerPartId=-1|Location.X=1078|Location.Y=816|Color=8388608|FontID=2|IsHidden=T|Text=AEC-Q200|Name=OTHER
|RECORD=41|OwnerIndex=334|IndexInSheet=10|OwnerPartId=-1|Location.X=1078|Location.Y=816|Color=8388608|FontID=2|IsHidden=T|Text=50V|Name=P2
|RECORD=41|OwnerIndex=334|IndexInSheet=11|OwnerPartId=-1|Location.X=1078|Location.Y=816|Color=8388608|FontID=2|IsHidden=T|Text=X7R|Name=P3
|RECORD=41|OwnerIndex=334|IndexInSheet=12|OwnerPartId=-1|Location.X=1078|Location.Y=816|Color=8388608|FontID=2|IsHidden=T|Text=0402|Name=Size
|RECORD=41|OwnerIndex=334|IndexInSheet=13|OwnerPartId=-1|Location.X=1078|Location.Y=816|Color=8388608|FontID=2|IsHidden=T|Name=SUB
|RECORD=41|OwnerIndex=334|IndexInSheet=14|OwnerPartId=-1|Location.X=1078|Location.Y=816|Color=8388608|FontID=1|IsHidden=T|Text=CAP, CER, 0.1UF, 50V, 10%, X7R, AEC-Q200, 0402|Name=DESC
|RECORD=41|OwnerIndex=334|IndexInSheet=15|OwnerPartId=-1|Location.X=1078|Location.Y=816|Color=8388608|FontID=1|IsHidden=T|Text=Digi-Key|Name=Supplier 1|ReadOnlyState=3
|RECORD=41|OwnerIndex=334|IndexInSheet=16|OwnerPartId=-1|Location.X=1078|Location.Y=816|Color=8388608|FontID=1|IsHidden=T|Text=445-6899-1-ND|Name=Supplier Part Number 1|ReadOnlyState=3
|RECORD=41|OwnerIndex=334|IndexInSheet=17|OwnerPartId=-1|Location.X=1101|Location.Y=798|Color=8388608|FontID=2|Text=0.1UF|Name=VALUE
|RECORD=2|OwnerIndex=334|OwnerPartId=1|FormalType=1|Electrical=4|PinConglomerate=32|PinLength=10|Location.X=1100|Location.Y=810|Name=2|Designator=2|SwapIdPin=2|SwapIDPart=1|PinPropagationDelay=0.000000E+000
|RECORD=2|OwnerIndex=334|OwnerPartId=1|FormalType=1|Electrical=4|PinConglomerate=34|PinLength=10|Location.X=1090|Location.Y=810|Name=1|Designator=1|SwapIdPin=1|SwapIDPart=1|PinPropagationDelay=0.000000E+000
|RECORD=13|OwnerIndex=334|IsNotAccesible=T|IndexInSheet=20|OwnerPartId=1|Location.X=1097|Location.X_Frac=50000|Location.Y=810|Corner.X=1100|Corner.Y=810|LineWidth=1|Color=16711680
|RECORD=13|OwnerIndex=334|IsNotAccesible=T|IndexInSheet=21|OwnerPartId=1|Location.X=1090|Location.Y=810|Corner.X=1092|Corner.X_Frac=50000|Corner.Y=810|LineWidth=1|Color=16711680
|RECORD=13|OwnerIndex=334|IsNotAccesible=T|IndexInSheet=22|OwnerPartId=1|Location.X=1097|Location.X_Frac=50000|Location.Y=815|Corner.X=1097|Corner.X_Frac=50000|Corner.Y=805|LineWidth=1|Color=16711680
|RECORD=13|OwnerIndex=334|IsNotAccesible=T|IndexInSheet=23|OwnerPartId=1|Location.X=1092|Location.X_Frac=50000|Location.Y=815|Corner.X=1092|Corner.X_Frac=50000|Corner.Y=805|LineWidth=1|Color=16711680
|RECORD=41|OwnerIndex=334|IndexInSheet=24|OwnerPartId=-1|Location.X=1078|Location.Y=816|Color=8388608|FontID=1|IsHidden=T|Text=<VALENTIUM>|Name=VALENTIUM PART NUM
|RECORD=34|OwnerIndex=334|IndexInSheet=-1|OwnerPartId=-1|Location.X=1070|Location.Y=796|Color=8388608|FontID=3|Text=C45|Name=Designator|ReadOnlyState=1
|RECORD=41|OwnerIndex=334|IndexInSheet=-1|OwnerPartId=-1|Location.X=1078|Location.Y=816|Color=8388608|FontID=2|IsHidden=T|Text=CAP_0402_0.1UF_50V|Name=Comment|ReadOnlyState=1
|RECORD=44|OwnerIndex=334
|RECORD=45|OwnerIndex=364|IndexInSheet=-1|Description=Chip Capacitor, 0402, 2-Leads, Body 1.00x0.50mm, IPC Medium Density|UseComponentLibrary=T|ModelName=CAPC1005X06N|ModelType=PCBLIB|DatafileCount=1|ModelDatafileEntity0=CAPC1005X06N|ModelDatafileKind0=PCBLib|IsCurrent=T|DatalinksLocked=T|DatabaseDatalinksLocked=T|IntegratedModel=T|DatabaseModel=T
|RECORD=46|OwnerIndex=365
|RECORD=48|OwnerIndex=365
|RECORD=1|LibReference=CAP_0402_0.1UF_50V|ComponentDescription=CAP, CER, 0.1UF, 50V, 10%, X7R, AEC-Q200, 0402|PartCount=2|DisplayModeCount=1|IndexInSheet=69|OwnerPartId=-1|Location.X=1090|Location.Y=800|Orientation=1|CurrentPartId=1|LibraryPath=*|SourceLibraryName=Capacitors.IntLib|TargetFileName=*|AreaColor=11599871|Color=128|PartIDLocked=F|DesignItemId=CAP_0402_0.1UF_50V|AllPinCount=2
|RECORD=41|OwnerIndex=368|OwnerPartId=-1|Location.X=1038|Location.Y=826|Color=8388608|FontID=2|IsHidden=T|Text=CAP, CER|Name=CATEGORY
|RECORD=41|OwnerIndex=368|IndexInSheet=1|OwnerPartId=-1|Location.X=1038|Location.Y=826|Color=8388608|FontID=2|IsHidden=T|Text=TDK|Name=MFG NAME
|RECORD=41|OwnerIndex=368|IndexInSheet=2|OwnerPartId=-1|Location.X=1038|Location.Y=826|Color=8388608|FontID=2|IsHidden=T|Text=CGA2B3X7R1H104K050BB|Name=MFG PART NUM
|RECORD=41|OwnerIndex=368|IndexInSheet=3|OwnerPartId=-1|Location.X=1038|Location.Y=826|Color=8388608|FontID=2|IsHidden=T|Text=10/23/2013|Name=MODIFY DATE
|RECORD=41|OwnerIndex=368|IndexInSheet=4|OwnerPartId=-1|Location.X=1038|Location.Y=826|Color=8388608|FontID=2|IsHidden=T|Name=Date
|RECORD=41|OwnerIndex=368|IndexInSheet=5|OwnerPartId=-1|Location.X=1038|Location.Y=826|Color=8388608|FontID=2|IsHidden=T|Text=*|Name=SHEETPART
|RECORD=41|OwnerIndex=368|IndexInSheet=6|OwnerPartId=-1|Location.X=1038|Location.Y=826|Color=8388608|FontID=2|IsHidden=T|Text=10%|Name=P1
|RECORD=41|OwnerIndex=368|IndexInSheet=7|OwnerPartId=-1|Location.X=1038|Location.Y=826|Color=8388608|FontID=2|IsHidden=T|Text=125C|Name=MAXTEMP
|RECORD=41|OwnerIndex=368|IndexInSheet=8|OwnerPartId=-1|Location.X=1038|Location.Y=826|Color=8388608|FontID=2|IsHidden=T|Text=-55C|Name=MINTEMP
|RECORD=41|OwnerIndex=368|IndexInSheet=9|OwnerPartId=-1|Location.X=1038|Location.Y=826|Color=8388608|FontID=2|IsHidden=T|Text=AEC-Q200|Name=OTHER
|RECORD=41|OwnerIndex=368|IndexInSheet=10|OwnerPartId=-1|Location.X=1038|Location.Y=826|Color=8388608|FontID=2|IsHidden=T|Text=50V|Name=P2
|RECORD=41|OwnerIndex=368|IndexInSheet=11|OwnerPartId=-1|Location.X=1038|Location.Y=826|Color=8388608|FontID=2|IsHidden=T|Text=X7R|Name=P3
|RECORD=41|OwnerIndex=368|IndexInSheet=12|OwnerPartId=-1|Location.X=1038|Location.Y=826|Color=8388608|FontID=2|IsHidden=T|Text=0402|Name=Size
|RECORD=41|OwnerIndex=368|IndexInSheet=13|OwnerPartId=-1|Location.X=1038|Location.Y=826|Color=8388608|FontID=2|IsHidden=T|Name=SUB
|RECORD=41|OwnerIndex=368|IndexInSheet=14|OwnerPartId=-1|Location.X=1038|Location.Y=826|Color=8388608|FontID=1|IsHidden=T|Text=CAP, CER, 0.1UF, 50V, 10%, X7R, AEC-Q200, 0402|Name=DESC
|RECORD=41|OwnerIndex=368|IndexInSheet=15|OwnerPartId=-1|Location.X=1038|Location.Y=826|Color=8388608|FontID=1|IsHidden=T|Text=Digi-Key|Name=Supplier 1|ReadOnlyState=3
|RECORD=41|OwnerIndex=368|IndexInSheet=16|OwnerPartId=-1|Location.X=1038|Location.Y=826|Color=8388608|FontID=1|IsHidden=T|Text=445-6899-1-ND|Name=Supplier Part Number 1|ReadOnlyState=3
|RECORD=41|OwnerIndex=368|IndexInSheet=17|OwnerPartId=-1|Location.X=1060|Location.Y=820|Color=8388608|FontID=2|Text=0.1UF|Name=VALUE
|RECORD=2|OwnerIndex=368|OwnerPartId=1|FormalType=1|Electrical=4|PinConglomerate=32|PinLength=10|Location.X=1060|Location.Y=820|Name=2|Designator=2|SwapIdPin=2|SwapIDPart=1|PinPropagationDelay=0.000000E+000
|RECORD=2|OwnerIndex=368|OwnerPartId=1|FormalType=1|Electrical=4|PinConglomerate=34|PinLength=10|Location.X=1050|Location.Y=820|Name=1|Designator=1|SwapIdPin=1|SwapIDPart=1|PinPropagationDelay=0.000000E+000
|RECORD=13|OwnerIndex=368|IsNotAccesible=T|IndexInSheet=20|OwnerPartId=1|Location.X=1057|Location.X_Frac=50000|Location.Y=820|Corner.X=1060|Corner.Y=820|LineWidth=1|Color=16711680
|RECORD=13|OwnerIndex=368|IsNotAccesible=T|IndexInSheet=21|OwnerPartId=1|Location.X=1050|Location.Y=820|Corner.X=1052|Corner.X_Frac=50000|Corner.Y=820|LineWidth=1|Color=16711680
|RECORD=13|OwnerIndex=368|IsNotAccesible=T|IndexInSheet=22|OwnerPartId=1|Location.X=1057|Location.X_Frac=50000|Location.Y=825|Corner.X=1057|Corner.X_Frac=50000|Corner.Y=815|LineWidth=1|Color=16711680
|RECORD=13|OwnerIndex=368|IsNotAccesible=T|IndexInSheet=23|OwnerPartId=1|Location.X=1052|Location.X_Frac=50000|Location.Y=825|Corner.X=1052|Corner.X_Frac=50000|Corner.Y=815|LineWidth=1|Color=16711680
|RECORD=41|OwnerIndex=368|IndexInSheet=24|OwnerPartId=-1|Location.X=1038|Location.Y=826|Color=8388608|FontID=1|IsHidden=T|Text=<VALENTIUM>|Name=VALENTIUM PART NUM
|RECORD=34|OwnerIndex=368|IndexInSheet=-1|OwnerPartId=-1|Location.X=1030|Location.Y=820|Color=8388608|FontID=3|Text=C44|Name=Designator|ReadOnlyState=1
|RECORD=41|OwnerIndex=368|IndexInSheet=-1|OwnerPartId=-1|Location.X=1038|Location.Y=826|Color=8388608|FontID=2|IsHidden=T|Text=CAP_0402_0.1UF_50V|Name=Comment|ReadOnlyState=1
|RECORD=44|OwnerIndex=368
|RECORD=45|OwnerIndex=398|IndexInSheet=-1|Description=Chip Capacitor, 0402, 2-Leads, Body 1.00x0.50mm, IPC Medium Density|UseComponentLibrary=T|ModelName=CAPC1005X06N|ModelType=PCBLIB|DatafileCount=1|ModelDatafileEntity0=CAPC1005X06N|ModelDatafileKind0=PCBLib|IsCurrent=T|DatalinksLocked=T|DatabaseDatalinksLocked=T|IntegratedModel=T|DatabaseModel=T
|RECORD=46|OwnerIndex=399
|RECORD=48|OwnerIndex=399
|RECORD=1|LibReference=CAP_0402_0.1UF_50V|ComponentDescription=CAP, CER, 0.1UF, 50V, 10%, X7R, AEC-Q200, 0402|PartCount=2|DisplayModeCount=1|IndexInSheet=70|OwnerPartId=-1|Location.X=1060|Location.Y=770|Orientation=1|CurrentPartId=1|LibraryPath=*|SourceLibraryName=Capacitors.IntLib|TargetFileName=*|AreaColor=11599871|Color=128|PartIDLocked=F|DesignItemId=CAP_0402_0.1UF_50V|AllPinCount=2
|RECORD=41|OwnerIndex=402|OwnerPartId=-1|Location.X=1008|Location.Y=796|Color=8388608|FontID=2|IsHidden=T|Text=CAP, CER|Name=CATEGORY
|RECORD=41|OwnerIndex=402|IndexInSheet=1|OwnerPartId=-1|Location.X=1008|Location.Y=796|Color=8388608|FontID=2|IsHidden=T|Text=TDK|Name=MFG NAME
|RECORD=41|OwnerIndex=402|IndexInSheet=2|OwnerPartId=-1|Location.X=1008|Location.Y=796|Color=8388608|FontID=2|IsHidden=T|Text=CGA2B3X7R1H104K050BB|Name=MFG PART NUM
|RECORD=41|OwnerIndex=402|IndexInSheet=3|OwnerPartId=-1|Location.X=1008|Location.Y=796|Color=8388608|FontID=2|IsHidden=T|Text=10/23/2013|Name=MODIFY DATE
|RECORD=41|OwnerIndex=402|IndexInSheet=4|OwnerPartId=-1|Location.X=1008|Location.Y=796|Color=8388608|FontID=2|IsHidden=T|Name=Date
|RECORD=41|OwnerIndex=402|IndexInSheet=5|OwnerPartId=-1|Location.X=1008|Location.Y=796|Color=8388608|FontID=2|IsHidden=T|Text=*|Name=SHEETPART
|RECORD=41|OwnerIndex=402|IndexInSheet=6|OwnerPartId=-1|Location.X=1008|Location.Y=796|Color=8388608|FontID=2|IsHidden=T|Text=10%|Name=P1
|RECORD=41|OwnerIndex=402|IndexInSheet=7|OwnerPartId=-1|Location.X=1008|Location.Y=796|Color=8388608|FontID=2|IsHidden=T|Text=125C|Name=MAXTEMP
|RECORD=41|OwnerIndex=402|IndexInSheet=8|OwnerPartId=-1|Location.X=1008|Location.Y=796|Color=8388608|FontID=2|IsHidden=T|Text=-55C|Name=MINTEMP
|RECORD=41|OwnerIndex=402|IndexInSheet=9|OwnerPartId=-1|Location.X=1008|Location.Y=796|Color=8388608|FontID=2|IsHidden=T|Text=AEC-Q200|Name=OTHER
|RECORD=41|OwnerIndex=402|IndexInSheet=10|OwnerPartId=-1|Location.X=1008|Location.Y=796|Color=8388608|FontID=2|IsHidden=T|Text=50V|Name=P2
|RECORD=41|OwnerIndex=402|IndexInSheet=11|OwnerPartId=-1|Location.X=1008|Location.Y=796|Color=8388608|FontID=2|IsHidden=T|Text=X7R|Name=P3
|RECORD=41|OwnerIndex=402|IndexInSheet=12|OwnerPartId=-1|Location.X=1008|Location.Y=796|Color=8388608|FontID=2|IsHidden=T|Text=0402|Name=Size
|RECORD=41|OwnerIndex=402|IndexInSheet=13|OwnerPartId=-1|Location.X=1008|Location.Y=796|Color=8388608|FontID=2|IsHidden=T|Name=SUB
|RECORD=41|OwnerIndex=402|IndexInSheet=14|OwnerPartId=-1|Location.X=1008|Location.Y=796|Color=8388608|FontID=1|IsHidden=T|Text=CAP, CER, 0.1UF, 50V, 10%, X7R, AEC-Q200, 0402|Name=DESC
|RECORD=41|OwnerIndex=402|IndexInSheet=15|OwnerPartId=-1|Location.X=1008|Location.Y=796|Color=8388608|FontID=1|IsHidden=T|Text=Digi-Key|Name=Supplier 1|ReadOnlyState=3
|RECORD=41|OwnerIndex=402|IndexInSheet=16|OwnerPartId=-1|Location.X=1008|Location.Y=796|Color=8388608|FontID=1|IsHidden=T|Text=445-6899-1-ND|Name=Supplier Part Number 1|ReadOnlyState=3
|RECORD=41|OwnerIndex=402|IndexInSheet=17|OwnerPartId=-1|Location.X=1030|Location.Y=790|Color=8388608|FontID=2|Text=0.1UF|Name=VALUE
|RECORD=2|OwnerIndex=402|OwnerPartId=1|FormalType=1|Electrical=4|PinConglomerate=32|PinLength=10|Location.X=1030|Location.Y=790|Name=2|Designator=2|SwapIdPin=2|SwapIDPart=1|PinPropagationDelay=0.000000E+000
|RECORD=2|OwnerIndex=402|OwnerPartId=1|FormalType=1|Electrical=4|PinConglomerate=34|PinLength=10|Location.X=1020|Location.Y=790|Name=1|Designator=1|SwapIdPin=1|SwapIDPart=1|PinPropagationDelay=0.000000E+000
|RECORD=13|OwnerIndex=402|IsNotAccesible=T|IndexInSheet=20|OwnerPartId=1|Location.X=1027|Location.X_Frac=50000|Location.Y=790|Corner.X=1030|Corner.Y=790|LineWidth=1|Color=16711680
|RECORD=13|OwnerIndex=402|IsNotAccesible=T|IndexInSheet=21|OwnerPartId=1|Location.X=1020|Location.Y=790|Corner.X=1022|Corner.X_Frac=50000|Corner.Y=790|LineWidth=1|Color=16711680
|RECORD=13|OwnerIndex=402|IsNotAccesible=T|IndexInSheet=22|OwnerPartId=1|Location.X=1027|Location.X_Frac=50000|Location.Y=795|Corner.X=1027|Corner.X_Frac=50000|Corner.Y=785|LineWidth=1|Color=16711680
|RECORD=13|OwnerIndex=402|IsNotAccesible=T|IndexInSheet=23|OwnerPartId=1|Location.X=1022|Location.X_Frac=50000|Location.Y=795|Corner.X=1022|Corner.X_Frac=50000|Corner.Y=785|LineWidth=1|Color=16711680
|RECORD=41|OwnerIndex=402|IndexInSheet=24|OwnerPartId=-1|Location.X=1008|Location.Y=796|Color=8388608|FontID=1|IsHidden=T|Text=<VALENTIUM>|Name=VALENTIUM PART NUM
|RECORD=34|OwnerIndex=402|IndexInSheet=-1|OwnerPartId=-1|Location.X=1000|Location.Y=790|Color=8388608|FontID=3|Text=C46|Name=Designator|ReadOnlyState=1
|RECORD=41|OwnerIndex=402|IndexInSheet=-1|OwnerPartId=-1|Location.X=1008|Location.Y=796|Color=8388608|FontID=2|IsHidden=T|Text=CAP_0402_0.1UF_50V|Name=Comment|ReadOnlyState=1
|RECORD=44|OwnerIndex=402
|RECORD=45|OwnerIndex=432|IndexInSheet=-1|Description=Chip Capacitor, 0402, 2-Leads, Body 1.00x0.50mm, IPC Medium Density|UseComponentLibrary=T|ModelName=CAPC1005X06N|ModelType=PCBLIB|DatafileCount=1|ModelDatafileEntity0=CAPC1005X06N|ModelDatafileKind0=PCBLib|IsCurrent=T|DatalinksLocked=T|DatabaseDatalinksLocked=T|IntegratedModel=T|DatabaseModel=T
|RECORD=46|OwnerIndex=433
|RECORD=48|OwnerIndex=433
|RECORD=1|LibReference=CAP_0402_0.1UF_50V|ComponentDescription=CAP, CER, 0.1UF, 50V, 10%, X7R, AEC-Q200, 0402|PartCount=2|DisplayModeCount=1|IndexInSheet=71|OwnerPartId=-1|Location.X=1090|Location.Y=720|Orientation=1|CurrentPartId=1|LibraryPath=*|SourceLibraryName=Capacitors.IntLib|TargetFileName=*|AreaColor=11599871|Color=128|PartIDLocked=F|DesignItemId=CAP_0402_0.1UF_50V|AllPinCount=2
|RECORD=41|OwnerIndex=436|OwnerPartId=-1|Location.X=1038|Location.Y=746|Color=8388608|FontID=2|IsHidden=T|Text=CAP, CER|Name=CATEGORY
|RECORD=41|OwnerIndex=436|IndexInSheet=1|OwnerPartId=-1|Location.X=1038|Location.Y=746|Color=8388608|FontID=2|IsHidden=T|Text=TDK|Name=MFG NAME
|RECORD=41|OwnerIndex=436|IndexInSheet=2|OwnerPartId=-1|Location.X=1038|Location.Y=746|Color=8388608|FontID=2|IsHidden=T|Text=CGA2B3X7R1H104K050BB|Name=MFG PART NUM
|RECORD=41|OwnerIndex=436|IndexInSheet=3|OwnerPartId=-1|Location.X=1038|Location.Y=746|Color=8388608|FontID=2|IsHidden=T|Text=10/23/2013|Name=MODIFY DATE
|RECORD=41|OwnerIndex=436|IndexInSheet=4|OwnerPartId=-1|Location.X=1038|Location.Y=746|Color=8388608|FontID=2|IsHidden=T|Name=Date
|RECORD=41|OwnerIndex=436|IndexInSheet=5|OwnerPartId=-1|Location.X=1038|Location.Y=746|Color=8388608|FontID=2|IsHidden=T|Text=*|Name=SHEETPART
|RECORD=41|OwnerIndex=436|IndexInSheet=6|OwnerPartId=-1|Location.X=1038|Location.Y=746|Color=8388608|FontID=2|IsHidden=T|Text=10%|Name=P1
|RECORD=41|OwnerIndex=436|IndexInSheet=7|OwnerPartId=-1|Location.X=1038|Location.Y=746|Color=8388608|FontID=2|IsHidden=T|Text=125C|Name=MAXTEMP
|RECORD=41|OwnerIndex=436|IndexInSheet=8|OwnerPartId=-1|Location.X=1038|Location.Y=746|Color=8388608|FontID=2|IsHidden=T|Text=-55C|Name=MINTEMP
|RECORD=41|OwnerIndex=436|IndexInSheet=9|OwnerPartId=-1|Location.X=1038|Location.Y=746|Color=8388608|FontID=2|IsHidden=T|Text=AEC-Q200|Name=OTHER
|RECORD=41|OwnerIndex=436|IndexInSheet=10|OwnerPartId=-1|Location.X=1038|Location.Y=746|Color=8388608|FontID=2|IsHidden=T|Text=50V|Name=P2
|RECORD=41|OwnerIndex=436|IndexInSheet=11|OwnerPartId=-1|Location.X=1038|Location.Y=746|Color=8388608|FontID=2|IsHidden=T|Text=X7R|Name=P3
|RECORD=41|OwnerIndex=436|IndexInSheet=12|OwnerPartId=-1|Location.X=1038|Location.Y=746|Color=8388608|FontID=2|IsHidden=T|Text=0402|Name=Size
|RECORD=41|OwnerIndex=436|IndexInSheet=13|OwnerPartId=-1|Location.X=1038|Location.Y=746|Color=8388608|FontID=2|IsHidden=T|Name=SUB
|RECORD=41|OwnerIndex=436|IndexInSheet=14|OwnerPartId=-1|Location.X=1038|Location.Y=746|Color=8388608|FontID=1|IsHidden=T|Text=CAP, CER, 0.1UF, 50V, 10%, X7R, AEC-Q200, 0402|Name=DESC
|RECORD=41|OwnerIndex=436|IndexInSheet=15|OwnerPartId=-1|Location.X=1038|Location.Y=746|Color=8388608|FontID=1|IsHidden=T|Text=Digi-Key|Name=Supplier 1|ReadOnlyState=3
|RECORD=41|OwnerIndex=436|IndexInSheet=16|OwnerPartId=-1|Location.X=1038|Location.Y=746|Color=8388608|FontID=1|IsHidden=T|Text=445-6899-1-ND|Name=Supplier Part Number 1|ReadOnlyState=3
|RECORD=41|OwnerIndex=436|IndexInSheet=17|OwnerPartId=-1|Location.X=1060|Location.Y=740|Color=8388608|FontID=2|Text=0.1UF|Name=VALUE
|RECORD=2|OwnerIndex=436|OwnerPartId=1|FormalType=1|Electrical=4|PinConglomerate=32|PinLength=10|Location.X=1060|Location.Y=740|Name=2|Designator=2|SwapIdPin=2|SwapIDPart=1|PinPropagationDelay=0.000000E+000
|RECORD=2|OwnerIndex=436|OwnerPartId=1|FormalType=1|Electrical=4|PinConglomerate=34|PinLength=10|Location.X=1050|Location.Y=740|Name=1|Designator=1|SwapIdPin=1|SwapIDPart=1|PinPropagationDelay=0.000000E+000
|RECORD=13|OwnerIndex=436|IsNotAccesible=T|IndexInSheet=20|OwnerPartId=1|Location.X=1057|Location.X_Frac=50000|Location.Y=740|Corner.X=1060|Corner.Y=740|LineWidth=1|Color=16711680
|RECORD=13|OwnerIndex=436|IsNotAccesible=T|IndexInSheet=21|OwnerPartId=1|Location.X=1050|Location.Y=740|Corner.X=1052|Corner.X_Frac=50000|Corner.Y=740|LineWidth=1|Color=16711680
|RECORD=13|OwnerIndex=436|IsNotAccesible=T|IndexInSheet=22|OwnerPartId=1|Location.X=1057|Location.X_Frac=50000|Location.Y=745|Corner.X=1057|Corner.X_Frac=50000|Corner.Y=735|LineWidth=1|Color=16711680
|RECORD=13|OwnerIndex=436|IsNotAccesible=T|IndexInSheet=23|OwnerPartId=1|Location.X=1052|Location.X_Frac=50000|Location.Y=745|Corner.X=1052|Corner.X_Frac=50000|Corner.Y=735|LineWidth=1|Color=16711680
|RECORD=41|OwnerIndex=436|IndexInSheet=24|OwnerPartId=-1|Location.X=1038|Location.Y=746|Color=8388608|FontID=1|IsHidden=T|Text=<VALENTIUM>|Name=VALENTIUM PART NUM
|RECORD=34|OwnerIndex=436|IndexInSheet=-1|OwnerPartId=-1|Location.X=1030|Location.Y=740|Color=8388608|FontID=3|Text=C48|Name=Designator|ReadOnlyState=1
|RECORD=41|OwnerIndex=436|IndexInSheet=-1|OwnerPartId=-1|Location.X=1038|Location.Y=746|Color=8388608|FontID=2|IsHidden=T|Text=CAP_0402_0.1UF_50V|Name=Comment|ReadOnlyState=1
|RECORD=44|OwnerIndex=436
|RECORD=45|OwnerIndex=466|IndexInSheet=-1|Description=Chip Capacitor, 0402, 2-Leads, Body 1.00x0.50mm, IPC Medium Density|UseComponentLibrary=T|ModelName=CAPC1005X06N|ModelType=PCBLIB|DatafileCount=1|ModelDatafileEntity0=CAPC1005X06N|ModelDatafileKind0=PCBLib|IsCurrent=T|DatalinksLocked=T|DatabaseDatalinksLocked=T|IntegratedModel=T|DatabaseModel=T
|RECORD=46|OwnerIndex=467
|RECORD=48|OwnerIndex=467
|RECORD=1|LibReference=CAP_0402_0.1UF_50V|ComponentDescription=CAP, CER, 0.1UF, 50V, 10%, X7R, AEC-Q200, 0402|PartCount=2|DisplayModeCount=1|IndexInSheet=72|OwnerPartId=-1|Location.X=1090|Location.Y=680|Orientation=1|CurrentPartId=1|LibraryPath=*|SourceLibraryName=Capacitors.IntLib|TargetFileName=*|AreaColor=11599871|Color=128|PartIDLocked=F|DesignItemId=CAP_0402_0.1UF_50V|AllPinCount=2
|RECORD=41|OwnerIndex=470|OwnerPartId=-1|Location.X=1038|Location.Y=706|Color=8388608|FontID=2|IsHidden=T|Text=CAP, CER|Name=CATEGORY
|RECORD=41|OwnerIndex=470|IndexInSheet=1|OwnerPartId=-1|Location.X=1038|Location.Y=706|Color=8388608|FontID=2|IsHidden=T|Text=TDK|Name=MFG NAME
|RECORD=41|OwnerIndex=470|IndexInSheet=2|OwnerPartId=-1|Location.X=1038|Location.Y=706|Color=8388608|FontID=2|IsHidden=T|Text=CGA2B3X7R1H104K050BB|Name=MFG PART NUM
|RECORD=41|OwnerIndex=470|IndexInSheet=3|OwnerPartId=-1|Location.X=1038|Location.Y=706|Color=8388608|FontID=2|IsHidden=T|Text=10/23/2013|Name=MODIFY DATE
|RECORD=41|OwnerIndex=470|IndexInSheet=4|OwnerPartId=-1|Location.X=1038|Location.Y=706|Color=8388608|FontID=2|IsHidden=T|Name=Date
|RECORD=41|OwnerIndex=470|IndexInSheet=5|OwnerPartId=-1|Location.X=1038|Location.Y=706|Color=8388608|FontID=2|IsHidden=T|Text=*|Name=SHEETPART
|RECORD=41|OwnerIndex=470|IndexInSheet=6|OwnerPartId=-1|Location.X=1038|Location.Y=706|Color=8388608|FontID=2|IsHidden=T|Text=10%|Name=P1
|RECORD=41|OwnerIndex=470|IndexInSheet=7|OwnerPartId=-1|Location.X=1038|Location.Y=706|Color=8388608|FontID=2|IsHidden=T|Text=125C|Name=MAXTEMP
|RECORD=41|OwnerIndex=470|IndexInSheet=8|OwnerPartId=-1|Location.X=1038|Location.Y=706|Color=8388608|FontID=2|IsHidden=T|Text=-55C|Name=MINTEMP
|RECORD=41|OwnerIndex=470|IndexInSheet=9|OwnerPartId=-1|Location.X=1038|Location.Y=706|Color=8388608|FontID=2|IsHidden=T|Text=AEC-Q200|Name=OTHER
|RECORD=41|OwnerIndex=470|IndexInSheet=10|OwnerPartId=-1|Location.X=1038|Location.Y=706|Color=8388608|FontID=2|IsHidden=T|Text=50V|Name=P2
|RECORD=41|OwnerIndex=470|IndexInSheet=11|OwnerPartId=-1|Location.X=1038|Location.Y=706|Color=8388608|FontID=2|IsHidden=T|Text=X7R|Name=P3
|RECORD=41|OwnerIndex=470|IndexInSheet=12|OwnerPartId=-1|Location.X=1038|Location.Y=706|Color=8388608|FontID=2|IsHidden=T|Text=0402|Name=Size
|RECORD=41|OwnerIndex=470|IndexInSheet=13|OwnerPartId=-1|Location.X=1038|Location.Y=706|Color=8388608|FontID=2|IsHidden=T|Name=SUB
|RECORD=41|OwnerIndex=470|IndexInSheet=14|OwnerPartId=-1|Location.X=1038|Location.Y=706|Color=8388608|FontID=1|IsHidden=T|Text=CAP, CER, 0.1UF, 50V, 10%, X7R, AEC-Q200, 0402|Name=DESC
|RECORD=41|OwnerIndex=470|IndexInSheet=15|OwnerPartId=-1|Location.X=1038|Location.Y=706|Color=8388608|FontID=1|IsHidden=T|Text=Digi-Key|Name=Supplier 1|ReadOnlyState=3
|RECORD=41|OwnerIndex=470|IndexInSheet=16|OwnerPartId=-1|Location.X=1038|Location.Y=706|Color=8388608|FontID=1|IsHidden=T|Text=445-6899-1-ND|Name=Supplier Part Number 1|ReadOnlyState=3
|RECORD=41|OwnerIndex=470|IndexInSheet=17|OwnerPartId=-1|Location.X=1060|Location.Y=700|Color=8388608|FontID=2|Text=0.1UF|Name=VALUE
|RECORD=2|OwnerIndex=470|OwnerPartId=1|FormalType=1|Electrical=4|PinConglomerate=32|PinLength=10|Location.X=1060|Location.Y=700|Name=2|Designator=2|SwapIdPin=2|SwapIDPart=1|PinPropagationDelay=0.000000E+000
|RECORD=2|OwnerIndex=470|OwnerPartId=1|FormalType=1|Electrical=4|PinConglomerate=34|PinLength=10|Location.X=1050|Location.Y=700|Name=1|Designator=1|SwapIdPin=1|SwapIDPart=1|PinPropagationDelay=0.000000E+000
|RECORD=13|OwnerIndex=470|IsNotAccesible=T|IndexInSheet=20|OwnerPartId=1|Location.X=1057|Location.X_Frac=50000|Location.Y=700|Corner.X=1060|Corner.Y=700|LineWidth=1|Color=16711680
|RECORD=13|OwnerIndex=470|IsNotAccesible=T|IndexInSheet=21|OwnerPartId=1|Location.X=1050|Location.Y=700|Corner.X=1052|Corner.X_Frac=50000|Corner.Y=700|LineWidth=1|Color=16711680
|RECORD=13|OwnerIndex=470|IsNotAccesible=T|IndexInSheet=22|OwnerPartId=1|Location.X=1057|Location.X_Frac=50000|Location.Y=705|Corner.X=1057|Corner.X_Frac=50000|Corner.Y=695|LineWidth=1|Color=16711680
|RECORD=13|OwnerIndex=470|IsNotAccesible=T|IndexInSheet=23|OwnerPartId=1|Location.X=1052|Location.X_Frac=50000|Location.Y=705|Corner.X=1052|Corner.X_Frac=50000|Corner.Y=695|LineWidth=1|Color=16711680
|RECORD=41|OwnerIndex=470|IndexInSheet=24|OwnerPartId=-1|Location.X=1038|Location.Y=706|Color=8388608|FontID=1|IsHidden=T|Text=<VALENTIUM>|Name=VALENTIUM PART NUM
|RECORD=34|OwnerIndex=470|IndexInSheet=-1|OwnerPartId=-1|Location.X=1030|Location.Y=700|Color=8388608|FontID=3|Text=C50|Name=Designator|ReadOnlyState=1
|RECORD=41|OwnerIndex=470|IndexInSheet=-1|OwnerPartId=-1|Location.X=1038|Location.Y=706|Color=8388608|FontID=2|IsHidden=T|Text=CAP_0402_0.1UF_50V|Name=Comment|ReadOnlyState=1
|RECORD=44|OwnerIndex=470
|RECORD=45|OwnerIndex=500|IndexInSheet=-1|Description=Chip Capacitor, 0402, 2-Leads, Body 1.00x0.50mm, IPC Medium Density|UseComponentLibrary=T|ModelName=CAPC1005X06N|ModelType=PCBLIB|DatafileCount=1|ModelDatafileEntity0=CAPC1005X06N|ModelDatafileKind0=PCBLib|IsCurrent=T|DatalinksLocked=T|DatabaseDatalinksLocked=T|IntegratedModel=T|DatabaseModel=T
|RECORD=46|OwnerIndex=501
|RECORD=48|OwnerIndex=501
|RECORD=1|LibReference=PCIex4|ComponentDescription=PCIE x4 Edge Connector,OrCAD Symbol,NC|PartCount=2|DisplayModeCount=1|IndexInSheet=73|OwnerPartId=-1|Location.X=770|Location.Y=960|CurrentPartId=1|LibraryPath=*|SourceLibraryName=Connectors.IntLib|TargetFileName=*|AreaColor=11599871|Color=128|PartIDLocked=T|DesignItemId=PCIex4|AllPinCount=64
|RECORD=41|OwnerIndex=504|OwnerPartId=1|Location.X=90|Location.Y=150|Color=8388608|FontID=1|IsHidden=T|Text=NC|Name=NOTE|NotAutoPosition=T
|RECORD=41|OwnerIndex=504|IndexInSheet=1|OwnerPartId=1|Location.X=90|Location.Y=150|Color=8388608|FontID=1|IsHidden=T|Text=451|Name=Part Number|NotAutoPosition=T
|RECORD=41|OwnerIndex=504|IndexInSheet=2|OwnerPartId=1|Location.X=90|Location.Y=150|Color=8388608|FontID=1|IsHidden=T|Text=NA|Name=Manufacturer|NotAutoPosition=T
|RECORD=41|OwnerIndex=504|IndexInSheet=3|OwnerPartId=1|Location.X=90|Location.Y=150|Color=8388608|FontID=1|IsHidden=T|Text=NA|Name=Vendor P/N|NotAutoPosition=T
|RECORD=41|OwnerIndex=504|IndexInSheet=4|OwnerPartId=1|Location.X=90|Location.Y=150|Color=8388608|FontID=1|IsHidden=T|Text=SMT|Name=Part Type|NotAutoPosition=T
|RECORD=4|OwnerIndex=504|IsNotAccesible=T|IndexInSheet=5|OwnerPartId=1|Location.X=774|Location.Y=837|Color=8388608|FontID=6|Text=KEY
|RECORD=4|OwnerIndex=504|IsNotAccesible=T|IndexInSheet=6|OwnerPartId=1|Location.X=890|Location.Y=838|Color=8388608|FontID=6|Text=KEY
|RECORD=14|OwnerIndex=504|IsNotAccesible=T|IndexInSheet=7|OwnerPartId=1|Location.X=770|Location.Y=620|Corner.X=910|Corner.Y=960|LineWidth=1|Color=128|AreaColor=11599871|IsSolid=T|Transparent=T
|RECORD=2|OwnerIndex=504|OwnerPartId=1|FormalType=1|Electrical=7|PinConglomerate=58|PinLength=10|Location.X=770|Location.Y=950|Name=+12v1|Designator=B1|SwapIDPart=Ž&Ž||PinPropagationDelay=0.000000E+000
|RECORD=2|OwnerIndex=504|OwnerPartId=1|FormalType=1|Electrical=7|PinConglomerate=58|PinLength=10|Location.X=770|Location.Y=940|Name=+12V2|Designator=B2|SwapIDPart=Ž&Ž||PinPropagationDelay=0.000000E+000
|RECORD=2|OwnerIndex=504|OwnerPartId=1|FormalType=1|Electrical=7|PinConglomerate=58|PinLength=10|Location.X=770|Location.Y=930|Name=+12V3|Designator=B3|SwapIDPart=Ž&Ž||PinPropagationDelay=0.000000E+000
|RECORD=2|OwnerIndex=504|OwnerPartId=1|FormalType=1|Electrical=7|PinConglomerate=58|PinLength=10|Location.X=770|Location.Y=920|Name=GND1|Designator=B4|SwapIDPart=Ž&Ž||PinPropagationDelay=0.000000E+000
|RECORD=2|OwnerIndex=504|OwnerPartId=1|FormalType=1|Electrical=4|PinConglomerate=58|PinLength=10|Location.X=770|Location.Y=910|Name=SMCLK|Designator=B5|SwapIDPart=Ž&Ž||PinPropagationDelay=0.000000E+000
|RECORD=2|OwnerIndex=504|OwnerPartId=1|FormalType=1|Electrical=4|PinConglomerate=58|PinLength=10|Location.X=770|Location.Y=900|Name=SMDATA|Designator=B6|SwapIDPart=Ž&Ž||PinPropagationDelay=0.000000E+000
|RECORD=2|OwnerIndex=504|OwnerPartId=1|FormalType=1|Electrical=7|PinConglomerate=58|PinLength=10|Location.X=770|Location.Y=890|Name=GND2|Designator=B7|SwapIDPart=Ž&Ž||PinPropagationDelay=0.000000E+000
|RECORD=2|OwnerIndex=504|OwnerPartId=1|FormalType=1|Electrical=7|PinConglomerate=58|PinLength=10|Location.X=770|Location.Y=880|Name=+3.3V1|Designator=B8|SwapIDPart=Ž&Ž||PinPropagationDelay=0.000000E+000
|RECORD=2|OwnerIndex=504|OwnerPartId=1|FormalType=1|Electrical=4|PinConglomerate=58|PinLength=10|Location.X=770|Location.Y=870|Name=JTAG/TRST_n|Designator=B9|SwapIDPart=Ž&Ž||PinPropagationDelay=0.000000E+000
|RECORD=2|OwnerIndex=504|OwnerPartId=1|FormalType=1|Electrical=4|PinConglomerate=58|PinLength=10|Location.X=770|Location.Y=860|Name=+3.3vaux|Designator=B10|SwapIDPart=Ž&Ž||PinPropagationDelay=0.000000E+000
|RECORD=2|OwnerIndex=504|OwnerPartId=1|FormalType=1|Electrical=4|PinConglomerate=58|PinLength=10|Location.X=770|Location.Y=850|Name=WAKE_n|Designator=B11|SwapIDPart=Ž&Ž||PinPropagationDelay=0.000000E+000
|RECORD=2|OwnerIndex=504|OwnerPartId=1|FormalType=1|Electrical=4|PinConglomerate=58|PinLength=10|Location.X=770|Location.Y=830|Name=RESERVED1|Designator=B12|SwapIDPart=Ž&Ž||PinPropagationDelay=0.000000E+000
|RECORD=2|OwnerIndex=504|OwnerPartId=1|FormalType=1|Electrical=7|PinConglomerate=58|PinLength=10|Location.X=770|Location.Y=820|Name=GND3|Designator=B13|SwapIDPart=Ž&Ž||PinPropagationDelay=0.000000E+000
|RECORD=2|OwnerIndex=504|OwnerPartId=1|FormalType=1|Electrical=4|PinConglomerate=58|PinLength=10|Location.X=770|Location.Y=810|Name=PETp0|Designator=B14|SwapIDPart=Ž&Ž||PinPropagationDelay=0.000000E+000
|RECORD=2|OwnerIndex=504|OwnerPartId=1|FormalType=1|Electrical=4|PinConglomerate=58|PinLength=10|Location.X=770|Location.Y=800|Name=PETn0|Designator=B15|SwapIDPart=Ž&Ž||PinPropagationDelay=0.000000E+000
|RECORD=2|OwnerIndex=504|OwnerPartId=1|FormalType=1|Electrical=7|PinConglomerate=58|PinLength=10|Location.X=770|Location.Y=790|Name=GND4|Designator=B16|SwapIDPart=Ž&Ž||PinPropagationDelay=0.000000E+000
|RECORD=2|OwnerIndex=504|OwnerPartId=1|FormalType=1|Electrical=4|PinConglomerate=58|PinLength=10|Location.X=770|Location.Y=780|Name=PRSNT2_n|Designator=B17|SwapIDPart=Ž&Ž||PinPropagationDelay=0.000000E+000
|RECORD=2|OwnerIndex=504|OwnerPartId=1|FormalType=1|Electrical=7|PinConglomerate=58|PinLength=10|Location.X=770|Location.Y=770|Name=GND5|Designator=B18|SwapIDPart=Ž&Ž||PinPropagationDelay=0.000000E+000
|RECORD=2|OwnerIndex=504|OwnerPartId=1|FormalType=1|Electrical=4|PinConglomerate=58|PinLength=10|Location.X=770|Location.Y=760|Name=PETp1|Designator=B19|SwapIDPart=Ž&Ž||PinPropagationDelay=0.000000E+000
|RECORD=2|OwnerIndex=504|OwnerPartId=1|FormalType=1|Electrical=4|PinConglomerate=58|PinLength=10|Location.X=770|Location.Y=750|Name=PETn1|Designator=B20|SwapIDPart=Ž&Ž||PinPropagationDelay=0.000000E+000
|RECORD=2|OwnerIndex=504|OwnerPartId=1|FormalType=1|Electrical=7|PinConglomerate=58|PinLength=10|Location.X=770|Location.Y=740|Name=GND6|Designator=B21|SwapIDPart=Ž&Ž||PinPropagationDelay=0.000000E+000
|RECORD=2|OwnerIndex=504|OwnerPartId=1|FormalType=1|Electrical=7|PinConglomerate=58|PinLength=10|Location.X=770|Location.Y=730|Name=GND7|Designator=B22|SwapIDPart=Ž&Ž||PinPropagationDelay=0.000000E+000
|RECORD=2|OwnerIndex=504|OwnerPartId=1|FormalType=1|Electrical=4|PinConglomerate=58|PinLength=10|Location.X=770|Location.Y=720|Name=PETp2|Designator=B23|SwapIDPart=Ž&Ž||PinPropagationDelay=0.000000E+000
|RECORD=2|OwnerIndex=504|OwnerPartId=1|FormalType=1|Electrical=4|PinConglomerate=58|PinLength=10|Location.X=770|Location.Y=710|Name=PETn2|Designator=B24|SwapIDPart=Ž&Ž||PinPropagationDelay=0.000000E+000
|RECORD=2|OwnerIndex=504|OwnerPartId=1|FormalType=1|Electrical=7|PinConglomerate=58|PinLength=10|Location.X=770|Location.Y=700|Name=GND8|Designator=B25|SwapIDPart=Ž&Ž||PinPropagationDelay=0.000000E+000
|RECORD=2|OwnerIndex=504|OwnerPartId=1|FormalType=1|Electrical=7|PinConglomerate=58|PinLength=10|Location.X=770|Location.Y=690|Name=GND9|Designator=B26|SwapIDPart=Ž&Ž||PinPropagationDelay=0.000000E+000
|RECORD=2|OwnerIndex=504|OwnerPartId=1|FormalType=1|Electrical=4|PinConglomerate=58|PinLength=10|Location.X=770|Location.Y=680|Name=PETp3|Designator=B27|SwapIDPart=Ž&Ž||PinPropagationDelay=0.000000E+000
|RECORD=2|OwnerIndex=504|OwnerPartId=1|FormalType=1|Electrical=4|PinConglomerate=58|PinLength=10|Location.X=770|Location.Y=670|Name=PETn3|Designator=B28|SwapIDPart=Ž&Ž||PinPropagationDelay=0.000000E+000
|RECORD=2|OwnerIndex=504|OwnerPartId=1|FormalType=1|Electrical=7|PinConglomerate=58|PinLength=10|Location.X=770|Location.Y=660|Name=GND10|Designator=B29|SwapIDPart=Ž&Ž||PinPropagationDelay=0.000000E+000
|RECORD=2|OwnerIndex=504|OwnerPartId=1|FormalType=1|Electrical=4|PinConglomerate=58|PinLength=10|Location.X=770|Location.Y=650|Name=RESERVED2|Designator=B30|SwapIDPart=Ž&Ž||PinPropagationDelay=0.000000E+000
|RECORD=2|OwnerIndex=504|OwnerPartId=1|FormalType=1|Electrical=4|PinConglomerate=58|PinLength=10|Location.X=770|Location.Y=640|Name=PRSNT4_n|Designator=B31|SwapIDPart=Ž&Ž||PinPropagationDelay=0.000000E+000
|RECORD=2|OwnerIndex=504|OwnerPartId=1|FormalType=1|Electrical=7|PinConglomerate=58|PinLength=10|Location.X=770|Location.Y=630|Name=GND11|Designator=B32|SwapIDPart=Ž&Ž||PinPropagationDelay=0.000000E+000
|RECORD=2|OwnerIndex=504|OwnerPartId=1|FormalType=1|Electrical=4|PinConglomerate=56|PinLength=10|Location.X=910|Location.Y=950|Name=PRSNT1_n|Designator=A1|SwapIDPart=Ž&Ž||PinPropagationDelay=0.000000E+000
|RECORD=2|OwnerIndex=504|OwnerPartId=1|FormalType=1|Electrical=4|PinConglomerate=56|PinLength=10|Location.X=910|Location.Y=940|Name=+12V5|Designator=A2|SwapIDPart=Ž&Ž||PinPropagationDelay=0.000000E+000
|RECORD=2|OwnerIndex=504|OwnerPartId=1|FormalType=1|Electrical=4|PinConglomerate=56|PinLength=10|Location.X=910|Location.Y=930|Name=+12V4|Designator=A3|SwapIDPart=Ž&Ž||PinPropagationDelay=0.000000E+000
|RECORD=2|OwnerIndex=504|OwnerPartId=1|FormalType=1|Electrical=7|PinConglomerate=56|PinLength=10|Location.X=910|Location.Y=920|Name=GND37|Designator=A4|SwapIDPart=Ž&Ž||PinPropagationDelay=0.000000E+000
|RECORD=2|OwnerIndex=504|OwnerPartId=1|FormalType=1|Electrical=4|PinConglomerate=56|PinLength=10|Location.X=910|Location.Y=910|Name=JTAG/TCK|Designator=A5|SwapIDPart=Ž&Ž||PinPropagationDelay=0.000000E+000
|RECORD=2|OwnerIndex=504|OwnerPartId=1|FormalType=1|Electrical=4|PinConglomerate=56|PinLength=10|Location.X=910|Location.Y=900|Name=JTAG/TDI|Designator=A6|SwapIDPart=Ž&Ž||PinPropagationDelay=0.000000E+000
|RECORD=2|OwnerIndex=504|OwnerPartId=1|FormalType=1|Electrical=4|PinConglomerate=56|PinLength=10|Location.X=910|Location.Y=890|Name=JTAG/TDO|Designator=A7|SwapIDPart=Ž&Ž||PinPropagationDelay=0.000000E+000
|RECORD=2|OwnerIndex=504|OwnerPartId=1|FormalType=1|Electrical=4|PinConglomerate=56|PinLength=10|Location.X=910|Location.Y=880|Name=JTAG/TMS|Designator=A8|SwapIDPart=Ž&Ž||PinPropagationDelay=0.000000E+000
|RECORD=2|OwnerIndex=504|OwnerPartId=1|FormalType=1|Electrical=4|PinConglomerate=56|PinLength=10|Location.X=910|Location.Y=870|Name=+3.3V3|Designator=A9|SwapIDPart=Ž&Ž||PinPropagationDelay=0.000000E+000
|RECORD=2|OwnerIndex=504|OwnerPartId=1|FormalType=1|Electrical=4|PinConglomerate=56|PinLength=10|Location.X=910|Location.Y=860|Name=+3.3V2|Designator=A10|SwapIDPart=Ž&Ž||PinPropagationDelay=0.000000E+000
|RECORD=2|OwnerIndex=504|OwnerPartId=1|FormalType=1|Electrical=4|PinConglomerate=56|PinLength=10|Location.X=910|Location.Y=850|Name=PERST|Designator=A11|SwapIDPart=Ž&Ž||PinPropagationDelay=0.000000E+000
|RECORD=2|OwnerIndex=504|OwnerPartId=1|FormalType=1|Electrical=7|PinConglomerate=56|PinLength=10|Location.X=910|Location.Y=830|Name=GND36|Designator=A12|SwapIDPart=Ž&Ž||PinPropagationDelay=0.000000E+000
|RECORD=2|OwnerIndex=504|OwnerPartId=1|FormalType=1|Electrical=4|PinConglomerate=56|PinLength=10|Location.X=910|Location.Y=820|Name=REFCLK+|Designator=A13|SwapIDPart=Ž&Ž||PinPropagationDelay=0.000000E+000
|RECORD=2|OwnerIndex=504|OwnerPartId=1|FormalType=1|Electrical=4|PinConglomerate=56|PinLength=10|Location.X=910|Location.Y=810|Name=REFCLK-|Designator=A14|SwapIDPart=Ž&Ž||PinPropagationDelay=0.000000E+000
|RECORD=2|OwnerIndex=504|OwnerPartId=1|FormalType=1|Electrical=7|PinConglomerate=56|PinLength=10|Location.X=910|Location.Y=800|Name=GND35|Designator=A15|SwapIDPart=Ž&Ž||PinPropagationDelay=0.000000E+000
|RECORD=2|OwnerIndex=504|OwnerPartId=1|FormalType=1|Electrical=4|PinConglomerate=56|PinLength=10|Location.X=910|Location.Y=790|Name=PERp0|Designator=A16|SwapIDPart=Ž&Ž||PinPropagationDelay=0.000000E+000
|RECORD=2|OwnerIndex=504|OwnerPartId=1|FormalType=1|Electrical=4|PinConglomerate=56|PinLength=10|Location.X=910|Location.Y=780|Name=PERn0|Designator=A17|SwapIDPart=Ž&Ž||PinPropagationDelay=0.000000E+000
|RECORD=2|OwnerIndex=504|OwnerPartId=1|FormalType=1|Electrical=7|PinConglomerate=56|PinLength=10|Location.X=910|Location.Y=770|Name=GND34|Designator=A18|SwapIDPart=Ž&Ž||PinPropagationDelay=0.000000E+000
|RECORD=2|OwnerIndex=504|OwnerPartId=1|FormalType=1|Electrical=4|PinConglomerate=56|PinLength=10|Location.X=910|Location.Y=760|Name=RESERVED5|Designator=A19|SwapIDPart=Ž&Ž||PinPropagationDelay=0.000000E+000
|RECORD=2|OwnerIndex=504|OwnerPartId=1|FormalType=1|Electrical=7|PinConglomerate=56|PinLength=10|Location.X=910|Location.Y=750|Name=GND33|Designator=A20|SwapIDPart=Ž&Ž||PinPropagationDelay=0.000000E+000
|RECORD=2|OwnerIndex=504|OwnerPartId=1|FormalType=1|Electrical=4|PinConglomerate=56|PinLength=10|Location.X=910|Location.Y=740|Name=PERp1|Designator=A21|SwapIDPart=Ž&Ž||PinPropagationDelay=0.000000E+000
|RECORD=2|OwnerIndex=504|OwnerPartId=1|FormalType=1|Electrical=4|PinConglomerate=56|PinLength=10|Location.X=910|Location.Y=730|Name=PERn1|Designator=A22|SwapIDPart=Ž&Ž||PinPropagationDelay=0.000000E+000
|RECORD=2|OwnerIndex=504|OwnerPartId=1|FormalType=1|Electrical=7|PinConglomerate=56|PinLength=10|Location.X=910|Location.Y=720|Name=GND32|Designator=A23|SwapIDPart=Ž&Ž||PinPropagationDelay=0.000000E+000
|RECORD=2|OwnerIndex=504|OwnerPartId=1|FormalType=1|Electrical=7|PinConglomerate=56|PinLength=10|Location.X=910|Location.Y=710|Name=GND31|Designator=A24|SwapIDPart=Ž&Ž||PinPropagationDelay=0.000000E+000
|RECORD=2|OwnerIndex=504|OwnerPartId=1|FormalType=1|Electrical=4|PinConglomerate=56|PinLength=10|Location.X=910|Location.Y=700|Name=PERp2|Designator=A25|SwapIDPart=Ž&Ž||PinPropagationDelay=0.000000E+000
|RECORD=2|OwnerIndex=504|OwnerPartId=1|FormalType=1|Electrical=4|PinConglomerate=56|PinLength=10|Location.X=910|Location.Y=690|Name=PERn2|Designator=A26|SwapIDPart=Ž&Ž||PinPropagationDelay=0.000000E+000
|RECORD=2|OwnerIndex=504|OwnerPartId=1|FormalType=1|Electrical=7|PinConglomerate=56|PinLength=10|Location.X=910|Location.Y=680|Name=GND30|Designator=A27|SwapIDPart=Ž&Ž||PinPropagationDelay=0.000000E+000
|RECORD=2|OwnerIndex=504|OwnerPartId=1|FormalType=1|Electrical=7|PinConglomerate=56|PinLength=10|Location.X=910|Location.Y=670|Name=GND29|Designator=A28|SwapIDPart=Ž&Ž||PinPropagationDelay=0.000000E+000
|RECORD=2|OwnerIndex=504|OwnerPartId=1|FormalType=1|Electrical=4|PinConglomerate=56|PinLength=10|Location.X=910|Location.Y=660|Name=PERp3|Designator=A29|SwapIDPart=Ž&Ž||PinPropagationDelay=0.000000E+000
|RECORD=2|OwnerIndex=504|OwnerPartId=1|FormalType=1|Electrical=4|PinConglomerate=56|PinLength=10|Location.X=910|Location.Y=650|Name=PERn3|Designator=A30|SwapIDPart=Ž&Ž||PinPropagationDelay=0.000000E+000
|RECORD=2|OwnerIndex=504|OwnerPartId=1|FormalType=1|Electrical=7|PinConglomerate=56|PinLength=10|Location.X=910|Location.Y=640|Name=GND28|Designator=A31|SwapIDPart=Ž&Ž||PinPropagationDelay=0.000000E+000
|RECORD=2|OwnerIndex=504|OwnerPartId=1|FormalType=1|Electrical=4|PinConglomerate=56|PinLength=10|Location.X=910|Location.Y=630|Name=RESERVED4|Designator=A32|SwapIDPart=Ž&Ž||PinPropagationDelay=0.000000E+000
|RECORD=34|OwnerIndex=504|IndexInSheet=-1|OwnerPartId=1|Location.X=770|Location.Y=963|Color=8388608|FontID=5|Text=P2|Name=Designator|ReadOnlyState=1|OverrideNotAutoPosition=T
|RECORD=41|OwnerIndex=504|IndexInSheet=-1|OwnerPartId=-1|Location.X=880|Location.Y=613|Color=8388608|FontID=5|Text=PCIex4|Name=Comment|NotAutoPosition=T
|RECORD=44|OwnerIndex=504
|RECORD=45|OwnerIndex=643|IndexInSheet=-1|Description=PCIE_4LANE_EDGE|UseComponentLibrary=T|ModelName=PCIE_4LANE_EDGE|ModelType=PCBLIB|DatafileCount=1|ModelDatafileEntity0=PCIE_4LANE_EDGE|ModelDatafileKind0=PCBLib|IsCurrent=T|DatalinksLocked=T|DatabaseDatalinksLocked=T|IntegratedModel=T|DatabaseModel=T
|RECORD=46|OwnerIndex=644
|RECORD=48|OwnerIndex=644
|RECORD=45|OwnerIndex=643|IndexInSheet=-1|ModelName=ALINX_FPGA|ModelType=PCBLIB|DatafileCount=1|ModelDatafileEntity0=ALINX_FPGA|ModelDatafileKind0=PCBLib|IntegratedModel=T|DatabaseModel=T
|RECORD=46|OwnerIndex=647
|RECORD=48|OwnerIndex=647
|RECORD=17|IndexInSheet=74|OwnerPartId=-1|Style=4|ShowNetName=T|Location.X=1010|Location.Y=330|Orientation=3|Color=128|FontID=1|Text=GND
|RECORD=22|IndexInSheet=75|OwnerPartId=-1|Location.X=980|Location.Y=360|Color=255|Orientation=1|Symbol=Thin Cross|IsActive=T|SuppressAll=T
|RECORD=22|IndexInSheet=76|OwnerPartId=-1|Location.X=880|Location.Y=360|Color=255|Orientation=1|Symbol=Thin Cross|IsActive=T|SuppressAll=T
|RECORD=17|IndexInSheet=77|OwnerPartId=-1|ShowNetName=T|Location.X=1030|Location.Y=410|Orientation=1|Color=128|FontID=1|Text=+3.3V
|RECORD=17|IndexInSheet=78|OwnerPartId=-1|Style=4|ShowNetName=T|Location.X=590|Location.Y=180|Orientation=3|Color=128|FontID=1|Text=GND
|RECORD=17|IndexInSheet=79|OwnerPartId=-1|Style=4|ShowNetName=T|Location.X=730|Location.Y=180|Orientation=3|Color=128|FontID=1|Text=GND
|RECORD=17|IndexInSheet=80|OwnerPartId=-1|Style=4|ShowNetName=T|Location.X=870|Location.Y=180|Orientation=3|Color=128|FontID=1|Text=GND
|RECORD=17|IndexInSheet=81|OwnerPartId=-1|Style=4|ShowNetName=T|Location.X=1010|Location.Y=180|Orientation=3|Color=128|FontID=1|Text=GND
|RECORD=17|IndexInSheet=82|OwnerPartId=-1|ShowNetName=T|Location.X=630|Location.Y=170|Orientation=3|Color=128|FontID=1|Text=+3.3V
|RECORD=17|IndexInSheet=83|OwnerPartId=-1|ShowNetName=T|Location.X=770|Location.Y=169|Orientation=3|Color=128|FontID=1|Text=+3.3V
|RECORD=17|IndexInSheet=84|OwnerPartId=-1|ShowNetName=T|Location.X=910|Location.Y=170|Orientation=3|Color=128|FontID=1|Text=+3.3V
|RECORD=17|IndexInSheet=85|OwnerPartId=-1|ShowNetName=T|Location.X=1050|Location.Y=170|Orientation=3|Color=128|FontID=1|Text=+3.3V
|RECORD=17|IndexInSheet=86|OwnerPartId=-1|ShowNetName=T|Location.X=730|Location.Y=430|Orientation=2|Color=255|FontID=1|Text=FPGA_TCK|IsCrossSheetConnector=T
|RECORD=17|IndexInSheet=87|OwnerPartId=-1|ShowNetName=T|Location.X=730|Location.Y=400|Orientation=2|Color=255|FontID=1|Text=FPGA_TDO|IsCrossSheetConnector=T
|RECORD=17|IndexInSheet=88|OwnerPartId=-1|ShowNetName=T|Location.X=730|Location.Y=370|Orientation=2|Color=255|FontID=1|Text=FPGA_TMS|IsCrossSheetConnector=T
|RECORD=17|IndexInSheet=89|OwnerPartId=-1|ShowNetName=T|Location.X=730|Location.Y=340|Orientation=2|Color=255|FontID=1|Text=FPGA_TDI|IsCrossSheetConnector=T
|RECORD=4|IndexInSheet=90|OwnerPartId=-1|Location.X=910|Location.Y=430|Color=8388608|FontID=4|Text=JTAG
|RECORD=1|LibReference=RES_0805_33|ComponentDescription=RES, 33 OHM, 1%, 1/8W, TF, 0805|PartCount=2|DisplayModeCount=1|IndexInSheet=91|OwnerPartId=-1|Location.X=790|Location.Y=430|CurrentPartId=1|LibraryPath=*|SourceLibraryName=Resistors.IntLib|TargetFileName=*|AreaColor=11599871|Color=128|PartIDLocked=F|DesignItemId=RES_0805_33|AllPinCount=2
|RECORD=41|OwnerIndex=667|OwnerPartId=-1|Location.X=790|Location.Y=430|Color=8388608|FontID=2|IsHidden=T|Text=CRCW080533R0FKEA|Name=MFG PART NUM
|RECORD=41|OwnerIndex=667|IndexInSheet=1|OwnerPartId=-1|Location.X=790|Location.Y=430|Color=8388608|FontID=2|IsHidden=T|Text=VISHAY/DALE|Name=MFG NAME
|RECORD=41|OwnerIndex=667|IndexInSheet=2|OwnerPartId=-1|Location.X=790|Location.Y=430|Color=8388608|FontID=2|IsHidden=T|Text=RES|Name=CATEGORY
|RECORD=41|OwnerIndex=667|IndexInSheet=3|OwnerPartId=-1|Location.X=790|Location.Y=430|Color=8388608|FontID=2|IsHidden=T|Text=7/26/2013|Name=ModifyDate
|RECORD=41|OwnerIndex=667|IndexInSheet=4|OwnerPartId=-1|Location.X=788|Location.Y=440|Color=8388608|FontID=2|IsHidden=T|Name=Date
|RECORD=41|OwnerIndex=667|IndexInSheet=5|OwnerPartId=-1|Location.X=778|Location.X_Frac=55769|Location.Y=440|Color=8388608|FontID=2|IsHidden=T|Text=1%|Name=P1
|RECORD=41|OwnerIndex=667|IndexInSheet=6|OwnerPartId=-1|Location.X=778|Location.X_Frac=55769|Location.Y=440|Color=8388608|FontID=2|IsHidden=T|Text=TF|Name=P3
|RECORD=41|OwnerIndex=667|IndexInSheet=7|OwnerPartId=-1|Location.X=778|Location.X_Frac=55769|Location.Y=440|Color=8388608|FontID=2|IsHidden=T|Text=1/8W|Name=P2
|RECORD=41|OwnerIndex=667|IndexInSheet=8|OwnerPartId=-1|Location.X=778|Location.X_Frac=55769|Location.Y=440|Color=8388608|FontID=2|IsHidden=T|Text=125C|Name=MAXTEMP
|RECORD=41|OwnerIndex=667|IndexInSheet=9|OwnerPartId=-1|Location.X=778|Location.X_Frac=55769|Location.Y=440|Color=8388608|FontID=2|IsHidden=T|Text=-55C|Name=MINTEMP
|RECORD=41|OwnerIndex=667|IndexInSheet=10|OwnerPartId=-1|Location.X=778|Location.X_Frac=55769|Location.Y=440|Color=8388608|FontID=2|IsHidden=T|Text=100PPM|Name=OTHER
|RECORD=41|OwnerIndex=667|IndexInSheet=11|OwnerPartId=-1|Location.X=778|Location.X_Frac=55769|Location.Y=440|Color=8388608|FontID=2|IsHidden=T|Text=0805|Name=SIZE
|RECORD=41|OwnerIndex=667|IndexInSheet=12|OwnerPartId=-1|Location.X=778|Location.X_Frac=55769|Location.Y=440|Color=8388608|FontID=2|IsHidden=T|Name=SUB
|RECORD=41|OwnerIndex=667|IndexInSheet=13|OwnerPartId=-1|Location.X=778|Location.X_Frac=55769|Location.Y=440|Color=8388608|FontID=2|IsHidden=T|Text=Digi-Key|Name=Supplier 1|ReadOnlyState=3
|RECORD=41|OwnerIndex=667|IndexInSheet=14|OwnerPartId=-1|Location.X=778|Location.X_Frac=55769|Location.Y=440|Color=8388608|FontID=2|IsHidden=T|Text=541-33.0CCT-ND|Name=Supplier Part Number 1|ReadOnlyState=3
|RECORD=41|OwnerIndex=667|IndexInSheet=15|OwnerPartId=-1|Location.X=773|Location.X_Frac=98077|Location.Y=416|Color=8388608|FontID=1|IsHidden=T|Text=*|Name=SHEETPART
|RECORD=41|OwnerIndex=667|IndexInSheet=16|OwnerPartId=-1|Location.X=773|Location.X_Frac=98077|Location.Y=444|Color=8388608|FontID=1|IsHidden=T|Text=RES, 33 OHM, 1%, 1/8W, TF, 0805|Name=DESC
|RECORD=41|OwnerIndex=667|IndexInSheet=17|OwnerPartId=-1|Location.X=799|Location.Y=414|Color=8388608|FontID=2|Text=33 OHM|Name=VALUE
|RECORD=2|OwnerIndex=667|OwnerPartId=1|FormalType=1|Electrical=4|PinConglomerate=34|PinLength=10|Location.X=800|Location.Y=430|Name=1|Designator=1|PinPropagationDelay=0.000000E+000
|RECORD=2|OwnerIndex=667|OwnerPartId=1|FormalType=1|Electrical=4|PinConglomerate=32|PinLength=10|Location.X=830|Location.Y=430|Name=2|Designator=2|PinPropagationDelay=0.000000E+000
|RECORD=6|OwnerIndex=667|IsNotAccesible=T|IndexInSheet=20|OwnerPartId=1|LineWidth=1|Color=16711680|LocationCount=7|X1=830|Y1=430|X2=827|Y2=433|X3=821|Y3=427|X4=815|Y4=433|X5=809|Y5=427|X6=803|Y6=433|X7=800|Y7=430
|RECORD=41|OwnerIndex=667|IndexInSheet=21|OwnerPartId=-1|Location.X=774|Location.X_Frac=61102|Location.Y=444|Color=8388608|FontID=1|IsHidden=T|Text=<VELENTIUM>|Name=VELENTIUM PART NUM
|RECORD=34|OwnerIndex=667|IndexInSheet=-1|OwnerPartId=-1|Location.X=799|Location.Y=434|Color=8388608|FontID=3|Text=R18|Name=Designator|ReadOnlyState=1
|RECORD=41|OwnerIndex=667|IndexInSheet=-1|OwnerPartId=-1|Location.X=810|Location.Y=420|Color=8388608|FontID=2|IsHidden=T|Text==MFG PART NUM|Name=Comment
|RECORD=44|OwnerIndex=667
|RECORD=45|OwnerIndex=694|IndexInSheet=-1|Description=Chip Resistor, 0805, 2-Leads, Body 2.05x1.25mm, IPC Medium Density|UseComponentLibrary=T|ModelName=RESC2012X50N|ModelType=PCBLIB|DatafileCount=1|ModelDatafileEntity0=RESC2012X50N|ModelDatafileKind0=PCBLib|IsCurrent=T|DatalinksLocked=T|DatabaseDatalinksLocked=T|IntegratedModel=T|DatabaseModel=T
|RECORD=46|OwnerIndex=695
|RECORD=48|OwnerIndex=695
|RECORD=1|LibReference=RES_0805_33|ComponentDescription=RES, 33 OHM, 1%, 1/8W, TF, 0805|PartCount=2|DisplayModeCount=1|IndexInSheet=92|OwnerPartId=-1|Location.X=790|Location.Y=400|CurrentPartId=1|LibraryPath=*|SourceLibraryName=Resistors.IntLib|TargetFileName=*|AreaColor=11599871|Color=128|PartIDLocked=F|DesignItemId=RES_0805_33|AllPinCount=2
|RECORD=41|OwnerIndex=698|OwnerPartId=-1|Location.X=790|Location.Y=400|Color=8388608|FontID=2|IsHidden=T|Text=CRCW080533R0FKEA|Name=MFG PART NUM
|RECORD=41|OwnerIndex=698|IndexInSheet=1|OwnerPartId=-1|Location.X=790|Location.Y=400|Color=8388608|FontID=2|IsHidden=T|Text=VISHAY/DALE|Name=MFG NAME
|RECORD=41|OwnerIndex=698|IndexInSheet=2|OwnerPartId=-1|Location.X=790|Location.Y=400|Color=8388608|FontID=2|IsHidden=T|Text=RES|Name=CATEGORY
|RECORD=41|OwnerIndex=698|IndexInSheet=3|OwnerPartId=-1|Location.X=790|Location.Y=400|Color=8388608|FontID=2|IsHidden=T|Text=7/26/2013|Name=ModifyDate
|RECORD=41|OwnerIndex=698|IndexInSheet=4|OwnerPartId=-1|Location.X=788|Location.Y=410|Color=8388608|FontID=2|IsHidden=T|Name=Date
|RECORD=41|OwnerIndex=698|IndexInSheet=5|OwnerPartId=-1|Location.X=778|Location.X_Frac=55769|Location.Y=410|Color=8388608|FontID=2|IsHidden=T|Text=1%|Name=P1
|RECORD=41|OwnerIndex=698|IndexInSheet=6|OwnerPartId=-1|Location.X=778|Location.X_Frac=55769|Location.Y=410|Color=8388608|FontID=2|IsHidden=T|Text=TF|Name=P3
|RECORD=41|OwnerIndex=698|IndexInSheet=7|OwnerPartId=-1|Location.X=778|Location.X_Frac=55769|Location.Y=410|Color=8388608|FontID=2|IsHidden=T|Text=1/8W|Name=P2
|RECORD=41|OwnerIndex=698|IndexInSheet=8|OwnerPartId=-1|Location.X=778|Location.X_Frac=55769|Location.Y=410|Color=8388608|FontID=2|IsHidden=T|Text=125C|Name=MAXTEMP
|RECORD=41|OwnerIndex=698|IndexInSheet=9|OwnerPartId=-1|Location.X=778|Location.X_Frac=55769|Location.Y=410|Color=8388608|FontID=2|IsHidden=T|Text=-55C|Name=MINTEMP
|RECORD=41|OwnerIndex=698|IndexInSheet=10|OwnerPartId=-1|Location.X=778|Location.X_Frac=55769|Location.Y=410|Color=8388608|FontID=2|IsHidden=T|Text=100PPM|Name=OTHER
|RECORD=41|OwnerIndex=698|IndexInSheet=11|OwnerPartId=-1|Location.X=778|Location.X_Frac=55769|Location.Y=410|Color=8388608|FontID=2|IsHidden=T|Text=0805|Name=SIZE
|RECORD=41|OwnerIndex=698|IndexInSheet=12|OwnerPartId=-1|Location.X=778|Location.X_Frac=55769|Location.Y=410|Color=8388608|FontID=2|IsHidden=T|Name=SUB
|RECORD=41|OwnerIndex=698|IndexInSheet=13|OwnerPartId=-1|Location.X=778|Location.X_Frac=55769|Location.Y=410|Color=8388608|FontID=2|IsHidden=T|Text=Digi-Key|Name=Supplier 1|ReadOnlyState=3
|RECORD=41|OwnerIndex=698|IndexInSheet=14|OwnerPartId=-1|Location.X=778|Location.X_Frac=55769|Location.Y=410|Color=8388608|FontID=2|IsHidden=T|Text=541-33.0CCT-ND|Name=Supplier Part Number 1|ReadOnlyState=3
|RECORD=41|OwnerIndex=698|IndexInSheet=15|OwnerPartId=-1|Location.X=773|Location.X_Frac=98077|Location.Y=386|Color=8388608|FontID=1|IsHidden=T|Text=*|Name=SHEETPART
|RECORD=41|OwnerIndex=698|IndexInSheet=16|OwnerPartId=-1|Location.X=773|Location.X_Frac=98077|Location.Y=414|Color=8388608|FontID=1|IsHidden=T|Text=RES, 33 OHM, 1%, 1/8W, TF, 0805|Name=DESC
|RECORD=41|OwnerIndex=698|IndexInSheet=17|OwnerPartId=-1|Location.X=799|Location.Y=384|Color=8388608|FontID=2|Text=33 OHM|Name=VALUE
|RECORD=2|OwnerIndex=698|OwnerPartId=1|FormalType=1|Electrical=4|PinConglomerate=34|PinLength=10|Location.X=800|Location.Y=400|Name=1|Designator=1|PinPropagationDelay=0.000000E+000
|RECORD=2|OwnerIndex=698|OwnerPartId=1|FormalType=1|Electrical=4|PinConglomerate=32|PinLength=10|Location.X=830|Location.Y=400|Name=2|Designator=2|PinPropagationDelay=0.000000E+000
|RECORD=6|OwnerIndex=698|IsNotAccesible=T|IndexInSheet=20|OwnerPartId=1|LineWidth=1|Color=16711680|LocationCount=7|X1=830|Y1=400|X2=827|Y2=403|X3=821|Y3=397|X4=815|Y4=403|X5=809|Y5=397|X6=803|Y6=403|X7=800|Y7=400
|RECORD=41|OwnerIndex=698|IndexInSheet=21|OwnerPartId=-1|Location.X=774|Location.X_Frac=61102|Location.Y=414|Color=8388608|FontID=1|IsHidden=T|Text=<VELENTIUM>|Name=VELENTIUM PART NUM
|RECORD=34|OwnerIndex=698|IndexInSheet=-1|OwnerPartId=-1|Location.X=799|Location.Y=404|Color=8388608|FontID=3|Text=R19|Name=Designator|ReadOnlyState=1
|RECORD=41|OwnerIndex=698|IndexInSheet=-1|OwnerPartId=-1|Location.X=810|Location.Y=390|Color=8388608|FontID=2|IsHidden=T|Text==MFG PART NUM|Name=Comment
|RECORD=44|OwnerIndex=698
|RECORD=45|OwnerIndex=725|IndexInSheet=-1|Description=Chip Resistor, 0805, 2-Leads, Body 2.05x1.25mm, IPC Medium Density|UseComponentLibrary=T|ModelName=RESC2012X50N|ModelType=PCBLIB|DatafileCount=1|ModelDatafileEntity0=RESC2012X50N|ModelDatafileKind0=PCBLib|IsCurrent=T|DatalinksLocked=T|DatabaseDatalinksLocked=T|IntegratedModel=T|DatabaseModel=T
|RECORD=46|OwnerIndex=726
|RECORD=48|OwnerIndex=726
|RECORD=1|LibReference=RES_0805_33|ComponentDescription=RES, 33 OHM, 1%, 1/8W, TF, 0805|PartCount=2|DisplayModeCount=1|IndexInSheet=93|OwnerPartId=-1|Location.X=790|Location.Y=370|CurrentPartId=1|LibraryPath=*|SourceLibraryName=Resistors.IntLib|TargetFileName=*|AreaColor=11599871|Color=128|PartIDLocked=F|DesignItemId=RES_0805_33|AllPinCount=2
|RECORD=41|OwnerIndex=729|OwnerPartId=-1|Location.X=790|Location.Y=370|Color=8388608|FontID=2|IsHidden=T|Text=CRCW080533R0FKEA|Name=MFG PART NUM
|RECORD=41|OwnerIndex=729|IndexInSheet=1|OwnerPartId=-1|Location.X=790|Location.Y=370|Color=8388608|FontID=2|IsHidden=T|Text=VISHAY/DALE|Name=MFG NAME
|RECORD=41|OwnerIndex=729|IndexInSheet=2|OwnerPartId=-1|Location.X=790|Location.Y=370|Color=8388608|FontID=2|IsHidden=T|Text=RES|Name=CATEGORY
|RECORD=41|OwnerIndex=729|IndexInSheet=3|OwnerPartId=-1|Location.X=790|Location.Y=370|Color=8388608|FontID=2|IsHidden=T|Text=7/26/2013|Name=ModifyDate
|RECORD=41|OwnerIndex=729|IndexInSheet=4|OwnerPartId=-1|Location.X=788|Location.Y=380|Color=8388608|FontID=2|IsHidden=T|Name=Date
|RECORD=41|OwnerIndex=729|IndexInSheet=5|OwnerPartId=-1|Location.X=778|Location.X_Frac=55769|Location.Y=380|Color=8388608|FontID=2|IsHidden=T|Text=1%|Name=P1
|RECORD=41|OwnerIndex=729|IndexInSheet=6|OwnerPartId=-1|Location.X=778|Location.X_Frac=55769|Location.Y=380|Color=8388608|FontID=2|IsHidden=T|Text=TF|Name=P3
|RECORD=41|OwnerIndex=729|IndexInSheet=7|OwnerPartId=-1|Location.X=778|Location.X_Frac=55769|Location.Y=380|Color=8388608|FontID=2|IsHidden=T|Text=1/8W|Name=P2
|RECORD=41|OwnerIndex=729|IndexInSheet=8|OwnerPartId=-1|Location.X=778|Location.X_Frac=55769|Location.Y=380|Color=8388608|FontID=2|IsHidden=T|Text=125C|Name=MAXTEMP
|RECORD=41|OwnerIndex=729|IndexInSheet=9|OwnerPartId=-1|Location.X=778|Location.X_Frac=55769|Location.Y=380|Color=8388608|FontID=2|IsHidden=T|Text=-55C|Name=MINTEMP
|RECORD=41|OwnerIndex=729|IndexInSheet=10|OwnerPartId=-1|Location.X=778|Location.X_Frac=55769|Location.Y=380|Color=8388608|FontID=2|IsHidden=T|Text=100PPM|Name=OTHER
|RECORD=41|OwnerIndex=729|IndexInSheet=11|OwnerPartId=-1|Location.X=778|Location.X_Frac=55769|Location.Y=380|Color=8388608|FontID=2|IsHidden=T|Text=0805|Name=SIZE
|RECORD=41|OwnerIndex=729|IndexInSheet=12|OwnerPartId=-1|Location.X=778|Location.X_Frac=55769|Location.Y=380|Color=8388608|FontID=2|IsHidden=T|Name=SUB
|RECORD=41|OwnerIndex=729|IndexInSheet=13|OwnerPartId=-1|Location.X=778|Location.X_Frac=55769|Location.Y=380|Color=8388608|FontID=2|IsHidden=T|Text=Digi-Key|Name=Supplier 1|ReadOnlyState=3
|RECORD=41|OwnerIndex=729|IndexInSheet=14|OwnerPartId=-1|Location.X=778|Location.X_Frac=55769|Location.Y=380|Color=8388608|FontID=2|IsHidden=T|Text=541-33.0CCT-ND|Name=Supplier Part Number 1|ReadOnlyState=3
|RECORD=41|OwnerIndex=729|IndexInSheet=15|OwnerPartId=-1|Location.X=773|Location.X_Frac=98077|Location.Y=356|Color=8388608|FontID=1|IsHidden=T|Text=*|Name=SHEETPART
|RECORD=41|OwnerIndex=729|IndexInSheet=16|OwnerPartId=-1|Location.X=773|Location.X_Frac=98077|Location.Y=384|Color=8388608|FontID=1|IsHidden=T|Text=RES, 33 OHM, 1%, 1/8W, TF, 0805|Name=DESC
|RECORD=41|OwnerIndex=729|IndexInSheet=17|OwnerPartId=-1|Location.X=799|Location.Y=354|Color=8388608|FontID=2|Text=33 OHM|Name=VALUE
|RECORD=2|OwnerIndex=729|OwnerPartId=1|FormalType=1|Electrical=4|PinConglomerate=34|PinLength=10|Location.X=800|Location.Y=370|Name=1|Designator=1|PinPropagationDelay=0.000000E+000
|RECORD=2|OwnerIndex=729|OwnerPartId=1|FormalType=1|Electrical=4|PinConglomerate=32|PinLength=10|Location.X=830|Location.Y=370|Name=2|Designator=2|PinPropagationDelay=0.000000E+000
|RECORD=6|OwnerIndex=729|IsNotAccesible=T|IndexInSheet=20|OwnerPartId=1|LineWidth=1|Color=16711680|LocationCount=7|X1=830|Y1=370|X2=827|Y2=373|X3=821|Y3=367|X4=815|Y4=373|X5=809|Y5=367|X6=803|Y6=373|X7=800|Y7=370
|RECORD=41|OwnerIndex=729|IndexInSheet=21|OwnerPartId=-1|Location.X=774|Location.X_Frac=61102|Location.Y=384|Color=8388608|FontID=1|IsHidden=T|Text=<VELENTIUM>|Name=VELENTIUM PART NUM
|RECORD=34|OwnerIndex=729|IndexInSheet=-1|OwnerPartId=-1|Location.X=799|Location.Y=374|Color=8388608|FontID=3|Text=R20|Name=Designator|ReadOnlyState=1
|RECORD=41|OwnerIndex=729|IndexInSheet=-1|OwnerPartId=-1|Location.X=810|Location.Y=360|Color=8388608|FontID=2|IsHidden=T|Text==MFG PART NUM|Name=Comment
|RECORD=44|OwnerIndex=729
|RECORD=45|OwnerIndex=756|IndexInSheet=-1|Description=Chip Resistor, 0805, 2-Leads, Body 2.05x1.25mm, IPC Medium Density|UseComponentLibrary=T|ModelName=RESC2012X50N|ModelType=PCBLIB|DatafileCount=1|ModelDatafileEntity0=RESC2012X50N|ModelDatafileKind0=PCBLib|IsCurrent=T|DatalinksLocked=T|DatabaseDatalinksLocked=T|IntegratedModel=T|DatabaseModel=T
|RECORD=46|OwnerIndex=757
|RECORD=48|OwnerIndex=757
|RECORD=1|LibReference=RES_0805_33|ComponentDescription=RES, 33 OHM, 1%, 1/8W, TF, 0805|PartCount=2|DisplayModeCount=1|IndexInSheet=94|OwnerPartId=-1|Location.X=790|Location.Y=340|CurrentPartId=1|LibraryPath=*|SourceLibraryName=Resistors.IntLib|TargetFileName=*|AreaColor=11599871|Color=128|PartIDLocked=F|DesignItemId=RES_0805_33|AllPinCount=2
|RECORD=41|OwnerIndex=760|OwnerPartId=-1|Location.X=790|Location.Y=340|Color=8388608|FontID=2|IsHidden=T|Text=CRCW080533R0FKEA|Name=MFG PART NUM
|RECORD=41|OwnerIndex=760|IndexInSheet=1|OwnerPartId=-1|Location.X=790|Location.Y=340|Color=8388608|FontID=2|IsHidden=T|Text=VISHAY/DALE|Name=MFG NAME
|RECORD=41|OwnerIndex=760|IndexInSheet=2|OwnerPartId=-1|Location.X=790|Location.Y=340|Color=8388608|FontID=2|IsHidden=T|Text=RES|Name=CATEGORY
|RECORD=41|OwnerIndex=760|IndexInSheet=3|OwnerPartId=-1|Location.X=790|Location.Y=340|Color=8388608|FontID=2|IsHidden=T|Text=7/26/2013|Name=ModifyDate
|RECORD=41|OwnerIndex=760|IndexInSheet=4|OwnerPartId=-1|Location.X=788|Location.Y=350|Color=8388608|FontID=2|IsHidden=T|Name=Date
|RECORD=41|OwnerIndex=760|IndexInSheet=5|OwnerPartId=-1|Location.X=778|Location.X_Frac=55769|Location.Y=350|Color=8388608|FontID=2|IsHidden=T|Text=1%|Name=P1
|RECORD=41|OwnerIndex=760|IndexInSheet=6|OwnerPartId=-1|Location.X=778|Location.X_Frac=55769|Location.Y=350|Color=8388608|FontID=2|IsHidden=T|Text=TF|Name=P3
|RECORD=41|OwnerIndex=760|IndexInSheet=7|OwnerPartId=-1|Location.X=778|Location.X_Frac=55769|Location.Y=350|Color=8388608|FontID=2|IsHidden=T|Text=1/8W|Name=P2
|RECORD=41|OwnerIndex=760|IndexInSheet=8|OwnerPartId=-1|Location.X=778|Location.X_Frac=55769|Location.Y=350|Color=8388608|FontID=2|IsHidden=T|Text=125C|Name=MAXTEMP
|RECORD=41|OwnerIndex=760|IndexInSheet=9|OwnerPartId=-1|Location.X=778|Location.X_Frac=55769|Location.Y=350|Color=8388608|FontID=2|IsHidden=T|Text=-55C|Name=MINTEMP
|RECORD=41|OwnerIndex=760|IndexInSheet=10|OwnerPartId=-1|Location.X=778|Location.X_Frac=55769|Location.Y=350|Color=8388608|FontID=2|IsHidden=T|Text=100PPM|Name=OTHER
|RECORD=41|OwnerIndex=760|IndexInSheet=11|OwnerPartId=-1|Location.X=778|Location.X_Frac=55769|Location.Y=350|Color=8388608|FontID=2|IsHidden=T|Text=0805|Name=SIZE
|RECORD=41|OwnerIndex=760|IndexInSheet=12|OwnerPartId=-1|Location.X=778|Location.X_Frac=55769|Location.Y=350|Color=8388608|FontID=2|IsHidden=T|Name=SUB
|RECORD=41|OwnerIndex=760|IndexInSheet=13|OwnerPartId=-1|Location.X=778|Location.X_Frac=55769|Location.Y=350|Color=8388608|FontID=2|IsHidden=T|Text=Digi-Key|Name=Supplier 1|ReadOnlyState=3
|RECORD=41|OwnerIndex=760|IndexInSheet=14|OwnerPartId=-1|Location.X=778|Location.X_Frac=55769|Location.Y=350|Color=8388608|FontID=2|IsHidden=T|Text=541-33.0CCT-ND|Name=Supplier Part Number 1|ReadOnlyState=3
|RECORD=41|OwnerIndex=760|IndexInSheet=15|OwnerPartId=-1|Location.X=773|Location.X_Frac=98077|Location.Y=326|Color=8388608|FontID=1|IsHidden=T|Text=*|Name=SHEETPART
|RECORD=41|OwnerIndex=760|IndexInSheet=16|OwnerPartId=-1|Location.X=773|Location.X_Frac=98077|Location.Y=354|Color=8388608|FontID=1|IsHidden=T|Text=RES, 33 OHM, 1%, 1/8W, TF, 0805|Name=DESC
|RECORD=41|OwnerIndex=760|IndexInSheet=17|OwnerPartId=-1|Location.X=799|Location.Y=324|Color=8388608|FontID=2|Text=33 OHM|Name=VALUE
|RECORD=2|OwnerIndex=760|OwnerPartId=1|FormalType=1|Electrical=4|PinConglomerate=34|PinLength=10|Location.X=800|Location.Y=340|Name=1|Designator=1|PinPropagationDelay=0.000000E+000
|RECORD=2|OwnerIndex=760|OwnerPartId=1|FormalType=1|Electrical=4|PinConglomerate=32|PinLength=10|Location.X=830|Location.Y=340|Name=2|Designator=2|PinPropagationDelay=0.000000E+000
|RECORD=6|OwnerIndex=760|IsNotAccesible=T|IndexInSheet=20|OwnerPartId=1|LineWidth=1|Color=16711680|LocationCount=7|X1=830|Y1=340|X2=827|Y2=343|X3=821|Y3=337|X4=815|Y4=343|X5=809|Y5=337|X6=803|Y6=343|X7=800|Y7=340
|RECORD=41|OwnerIndex=760|IndexInSheet=21|OwnerPartId=-1|Location.X=774|Location.X_Frac=61102|Location.Y=354|Color=8388608|FontID=1|IsHidden=T|Text=<VELENTIUM>|Name=VELENTIUM PART NUM
|RECORD=34|OwnerIndex=760|IndexInSheet=-1|OwnerPartId=-1|Location.X=799|Location.Y=344|Color=8388608|FontID=3|Text=R21|Name=Designator|ReadOnlyState=1
|RECORD=41|OwnerIndex=760|IndexInSheet=-1|OwnerPartId=-1|Location.X=810|Location.Y=330|Color=8388608|FontID=2|IsHidden=T|Text==MFG PART NUM|Name=Comment
|RECORD=44|OwnerIndex=760
|RECORD=45|OwnerIndex=787|IndexInSheet=-1|Description=Chip Resistor, 0805, 2-Leads, Body 2.05x1.25mm, IPC Medium Density|UseComponentLibrary=T|ModelName=RESC2012X50N|ModelType=PCBLIB|DatafileCount=1|ModelDatafileEntity0=RESC2012X50N|ModelDatafileKind0=PCBLib|IsCurrent=T|DatalinksLocked=T|DatabaseDatalinksLocked=T|IntegratedModel=T|DatabaseModel=T
|RECORD=46|OwnerIndex=788
|RECORD=48|OwnerIndex=788
|RECORD=1|LibReference=SAMTEC-HTSH-105-01-L-DV|ComponentDescription=CONN, HDR, 2X5, VERT, 0.1IN  SHROUDED, SMT, HTSH SERIES|PartCount=2|DisplayModeCount=1|IndexInSheet=95|OwnerPartId=-1|Location.X=870|Location.Y=390|CurrentPartId=1|LibraryPath=*|SourceLibraryName=Connectors.IntLib|TargetFileName=*|AreaColor=11599871|Color=128|PartIDLocked=F|DesignItemId=SAMTEC-HTSH-105-01-L-DV|AllPinCount=10
|RECORD=41|OwnerIndex=791|OwnerPartId=-1|Location.X=870|Location.Y=390|Color=8388608|FontID=2|IsHidden=T|Text=HTST-105-01-L-DV-A|Name=MFG PART NUM
|RECORD=41|OwnerIndex=791|IndexInSheet=1|OwnerPartId=-1|Location.X=870|Location.Y=390|Color=8388608|FontID=2|IsHidden=T|Text=10/10/2013|Name=MODIFY DATE
|RECORD=41|OwnerIndex=791|IndexInSheet=2|OwnerPartId=-1|Location.X=870|Location.Y=390|Color=8388608|FontID=2|IsHidden=T|Text=SAMTEC INC|Name=MFG NAME
|RECORD=41|OwnerIndex=791|IndexInSheet=3|OwnerPartId=-1|Location.X=868|Location.Y=415|Color=8388608|FontID=2|IsHidden=T|Text=CONN, HDR|Name=CATEGORY
|RECORD=41|OwnerIndex=791|IndexInSheet=4|OwnerPartId=-1|Location.X=868|Location.Y=415|Color=8388608|FontID=2|IsHidden=T|Text=125C|Name=MAXTEMP
|RECORD=41|OwnerIndex=791|IndexInSheet=5|OwnerPartId=-1|Location.X=868|Location.Y=415|Color=8388608|FontID=2|IsHidden=T|Text=-55C|Name=MINTEMP
|RECORD=41|OwnerIndex=791|IndexInSheet=6|OwnerPartId=-1|Location.X=868|Location.Y=415|Color=8388608|FontID=2|IsHidden=T|Text=HTSH SERIES|Name=OTHER
|RECORD=41|OwnerIndex=791|IndexInSheet=7|OwnerPartId=-1|Location.X=868|Location.Y=415|Color=8388608|FontID=2|IsHidden=T|Text=VERT|Name=P1
|RECORD=41|OwnerIndex=791|IndexInSheet=8|OwnerPartId=-1|Location.X=868|Location.Y=415|Color=8388608|FontID=2|IsHidden=T|Text=0.1 IN|Name=P2
|RECORD=41|OwnerIndex=791|IndexInSheet=9|OwnerPartId=-1|Location.X=868|Location.Y=415|Color=8388608|FontID=2|IsHidden=T|Text=SHROUDED|Name=P3
|RECORD=41|OwnerIndex=791|IndexInSheet=10|OwnerPartId=-1|Location.X=868|Location.Y=415|Color=8388608|FontID=2|IsHidden=T|Text=SMT|Name=SIZE
|RECORD=41|OwnerIndex=791|IndexInSheet=11|OwnerPartId=-1|Location.X=868|Location.Y=415|Color=8388608|FontID=2|IsHidden=T|Name=SUB
|RECORD=41|OwnerIndex=791|IndexInSheet=12|OwnerPartId=-1|Location.X=868|Location.Y=309|Color=8388608|FontID=2|IsHidden=T|Name=SHEETPART
|RECORD=41|OwnerIndex=791|IndexInSheet=13|OwnerPartId=-1|Location.X=868|Location.Y=309|Color=8388608|FontID=2|IsHidden=T|Name=DATE
|RECORD=41|OwnerIndex=791|IndexInSheet=14|OwnerPartId=-1|Location.X=868|Location.Y=419|Color=8388608|FontID=1|IsHidden=T|Text=CONN, HDR, 2X5, VERT, 0.1IN  SHROUDED, SMT, HTSH SERIES|Name=DESC
|RECORD=41|OwnerIndex=791|IndexInSheet=15|OwnerPartId=-1|Location.X=868|Location.Y=419|Color=8388608|FontID=1|IsHidden=T|Text=<VALENTIUM>|Name=VALENTIUM PART NUM
|RECORD=41|OwnerIndex=791|IndexInSheet=16|OwnerPartId=-1|Location.X=860|Location.Y=422|Color=8388608|FontID=1|IsHidden=T|Text=Digi-Key|Name=Supplier 1|ReadOnlyState=3
|RECORD=41|OwnerIndex=791|IndexInSheet=17|OwnerPartId=-1|Location.X=860|Location.Y=422|Color=8388608|FontID=1|IsHidden=T|Text=SAM8809-ND|Name=Supplier Part Number 1|ReadOnlyState=3
|RECORD=41|OwnerIndex=791|IndexInSheet=18|OwnerPartId=-1|Location.X=908|Location.X_Frac=50000|Location.Y=328|Color=8388608|FontID=2|Text=2X5|Name=VALUE
|RECORD=2|OwnerIndex=791|OwnerPartId=1|FormalType=1|Electrical=4|PinConglomerate=50|PinLength=30|Location.X=910|Location.Y=350|Name=P9|Designator=9|PinPropagationDelay=0.000000E+000
|RECORD=2|OwnerIndex=791|OwnerPartId=1|FormalType=1|Electrical=4|PinConglomerate=50|PinLength=30|Location.X=910|Location.Y=380|Name=P3|Designator=3|PinPropagationDelay=0.000000E+000
|RECORD=2|OwnerIndex=791|OwnerPartId=1|FormalType=1|Electrical=4|PinConglomerate=48|PinLength=30|Location.X=950|Location.Y=350|Name=P10|Designator=10|PinPropagationDelay=0.000000E+000
|RECORD=2|OwnerIndex=791|OwnerPartId=1|FormalType=1|Electrical=4|PinConglomerate=48|PinLength=30|Location.X=950|Location.Y=380|Name=P4|Designator=4|PinPropagationDelay=0.000000E+000
|RECORD=2|OwnerIndex=791|OwnerPartId=1|FormalType=1|Electrical=4|PinConglomerate=50|PinLength=30|Location.X=910|Location.Y=390|Name=P1|Designator=1|PinPropagationDelay=0.000000E+000
|RECORD=2|OwnerIndex=791|OwnerPartId=1|FormalType=1|Electrical=4|PinConglomerate=50|PinLength=30|Location.X=910|Location.Y=370|Name=P5|Designator=5|PinPropagationDelay=0.000000E+000
|RECORD=2|OwnerIndex=791|OwnerPartId=1|FormalType=1|Electrical=4|PinConglomerate=50|PinLength=30|Location.X=910|Location.Y=360|Name=P7|Designator=7|PinPropagationDelay=0.000000E+000
|RECORD=2|OwnerIndex=791|OwnerPartId=1|FormalType=1|Electrical=4|PinConglomerate=48|PinLength=30|Location.X=950|Location.Y=390|Name=P2|Designator=2|PinPropagationDelay=0.000000E+000
|RECORD=2|OwnerIndex=791|OwnerPartId=1|FormalType=1|Electrical=4|PinConglomerate=48|PinLength=30|Location.X=950|Location.Y=370|Name=P6|Designator=6|PinPropagationDelay=0.000000E+000
|RECORD=2|OwnerIndex=791|OwnerPartId=1|FormalType=1|Electrical=4|PinConglomerate=48|PinLength=30|Location.X=950|Location.Y=360|Name=P8|Designator=8|PinPropagationDelay=0.000000E+000
|RECORD=13|OwnerIndex=791|IsNotAccesible=T|IndexInSheet=29|OwnerPartId=1|Location.X=917|Location.X_Frac=50000|Location.Y=365|Corner.X=922|Corner.X_Frac=50000|Corner.Y=360|LineWidth=1|Color=16711680
|RECORD=13|OwnerIndex=791|IsNotAccesible=T|IndexInSheet=30|OwnerPartId=1|Location.X=917|Location.X_Frac=50000|Location.Y=355|Corner.X=922|Corner.X_Frac=50000|Corner.Y=360|LineWidth=1|Color=16711680
|RECORD=13|OwnerIndex=791|IsNotAccesible=T|IndexInSheet=31|OwnerPartId=1|Location.X=917|Location.X_Frac=50000|Location.Y=355|Corner.X=922|Corner.X_Frac=50000|Corner.Y=350|LineWidth=1|Color=16711680
|RECORD=13|OwnerIndex=791|IsNotAccesible=T|IndexInSheet=32|OwnerPartId=1|Location.X=917|Location.X_Frac=50000|Location.Y=345|Corner.X=922|Corner.X_Frac=50000|Corner.Y=350|LineWidth=1|Color=16711680
|RECORD=13|OwnerIndex=791|IsNotAccesible=T|IndexInSheet=33|OwnerPartId=1|Location.X=917|Location.X_Frac=50000|Location.Y=395|Corner.X=922|Corner.X_Frac=50000|Corner.Y=390|LineWidth=1|Color=16711680
|RECORD=13|OwnerIndex=791|IsNotAccesible=T|IndexInSheet=34|OwnerPartId=1|Location.X=917|Location.X_Frac=50000|Location.Y=385|Corner.X=922|Corner.X_Frac=50000|Corner.Y=390|LineWidth=1|Color=16711680
|RECORD=13|OwnerIndex=791|IsNotAccesible=T|IndexInSheet=35|OwnerPartId=1|Location.X=917|Location.X_Frac=50000|Location.Y=385|Corner.X=922|Corner.X_Frac=50000|Corner.Y=380|LineWidth=1|Color=16711680
|RECORD=13|OwnerIndex=791|IsNotAccesible=T|IndexInSheet=36|OwnerPartId=1|Location.X=917|Location.X_Frac=50000|Location.Y=375|Corner.X=922|Corner.X_Frac=50000|Corner.Y=380|LineWidth=1|Color=16711680
|RECORD=13|OwnerIndex=791|IsNotAccesible=T|IndexInSheet=37|OwnerPartId=1|Location.X=942|Location.X_Frac=50000|Location.Y=355|Corner.X=937|Corner.X_Frac=50000|Corner.Y=350|LineWidth=1|Color=16711680
|RECORD=13|OwnerIndex=791|IsNotAccesible=T|IndexInSheet=38|OwnerPartId=1|Location.X=942|Location.X_Frac=50000|Location.Y=355|Corner.X=937|Corner.X_Frac=50000|Corner.Y=360|LineWidth=1|Color=16711680
|RECORD=13|OwnerIndex=791|IsNotAccesible=T|IndexInSheet=39|OwnerPartId=1|Location.X=942|Location.X_Frac=50000|Location.Y=365|Corner.X=937|Corner.X_Frac=50000|Corner.Y=360|LineWidth=1|Color=16711680
|RECORD=13|OwnerIndex=791|IsNotAccesible=T|IndexInSheet=40|OwnerPartId=1|Location.X=942|Location.X_Frac=50000|Location.Y=345|Corner.X=937|Corner.X_Frac=50000|Corner.Y=350|LineWidth=1|Color=16711680
|RECORD=13|OwnerIndex=791|IsNotAccesible=T|IndexInSheet=41|OwnerPartId=1|Location.X=942|Location.X_Frac=50000|Location.Y=375|Corner.X=937|Corner.X_Frac=50000|Corner.Y=380|LineWidth=1|Color=16711680
|RECORD=13|OwnerIndex=791|IsNotAccesible=T|IndexInSheet=42|OwnerPartId=1|Location.X=942|Location.X_Frac=50000|Location.Y=385|Corner.X=937|Corner.X_Frac=50000|Corner.Y=380|LineWidth=1|Color=16711680
|RECORD=13|OwnerIndex=791|IsNotAccesible=T|IndexInSheet=43|OwnerPartId=1|Location.X=942|Location.X_Frac=50000|Location.Y=385|Corner.X=937|Corner.X_Frac=50000|Corner.Y=390|LineWidth=1|Color=16711680
|RECORD=13|OwnerIndex=791|IsNotAccesible=T|IndexInSheet=44|OwnerPartId=1|Location.X=942|Location.X_Frac=50000|Location.Y=395|Corner.X=937|Corner.X_Frac=50000|Corner.Y=390|LineWidth=1|Color=16711680
|RECORD=13|OwnerIndex=791|IsNotAccesible=T|IndexInSheet=45|OwnerPartId=1|Location.X=917|Location.X_Frac=50000|Location.Y=375|Corner.X=922|Corner.X_Frac=50000|Corner.Y=370|LineWidth=1|Color=16711680
|RECORD=13|OwnerIndex=791|IsNotAccesible=T|IndexInSheet=46|OwnerPartId=1|Location.X=917|Location.X_Frac=50000|Location.Y=365|Corner.X=922|Corner.X_Frac=50000|Corner.Y=370|LineWidth=1|Color=16711680
|RECORD=13|OwnerIndex=791|IsNotAccesible=T|IndexInSheet=47|OwnerPartId=1|Location.X=942|Location.X_Frac=50000|Location.Y=365|Corner.X=937|Corner.X_Frac=50000|Corner.Y=370|LineWidth=1|Color=16711680
|RECORD=13|OwnerIndex=791|IsNotAccesible=T|IndexInSheet=48|OwnerPartId=1|Location.X=942|Location.X_Frac=50000|Location.Y=375|Corner.X=937|Corner.X_Frac=50000|Corner.Y=370|LineWidth=1|Color=16711680
|RECORD=13|OwnerIndex=791|IsNotAccesible=T|IndexInSheet=49|OwnerPartId=1|Location.X=950|Location.Y=350|Corner.X=937|Corner.X_Frac=50000|Corner.Y=350|LineWidth=1|Color=16711680
|RECORD=13|OwnerIndex=791|IsNotAccesible=T|IndexInSheet=50|OwnerPartId=1|Location.X=950|Location.Y=360|Corner.X=937|Corner.X_Frac=50000|Corner.Y=360|LineWidth=1|Color=16711680
|RECORD=13|OwnerIndex=791|IsNotAccesible=T|IndexInSheet=51|OwnerPartId=1|Location.X=950|Location.Y=370|Corner.X=937|Corner.X_Frac=50000|Corner.Y=370|LineWidth=1|Color=16711680
|RECORD=13|OwnerIndex=791|IsNotAccesible=T|IndexInSheet=52|OwnerPartId=1|Location.X=950|Location.Y=380|Corner.X=937|Corner.X_Frac=50000|Corner.Y=380|LineWidth=1|Color=16711680
|RECORD=13|OwnerIndex=791|IsNotAccesible=T|IndexInSheet=53|OwnerPartId=1|Location.X=950|Location.Y=390|Corner.X=937|Corner.X_Frac=50000|Corner.Y=390|LineWidth=1|Color=16711680
|RECORD=13|OwnerIndex=791|IsNotAccesible=T|IndexInSheet=54|OwnerPartId=1|Location.X=922|Location.Y=390|Corner.X=909|Corner.X_Frac=50000|Corner.Y=390|LineWidth=1|Color=16711680
|RECORD=13|OwnerIndex=791|IsNotAccesible=T|IndexInSheet=55|OwnerPartId=1|Location.X=922|Location.Y=380|Corner.X=909|Corner.X_Frac=50000|Corner.Y=380|LineWidth=1|Color=16711680
|RECORD=13|OwnerIndex=791|IsNotAccesible=T|IndexInSheet=56|OwnerPartId=1|Location.X=922|Location.Y=370|Corner.X=909|Corner.X_Frac=50000|Corner.Y=370|LineWidth=1|Color=16711680
|RECORD=13|OwnerIndex=791|IsNotAccesible=T|IndexInSheet=57|OwnerPartId=1|Location.X=922|Location.Y=360|Corner.X=909|Corner.X_Frac=50000|Corner.Y=360|LineWidth=1|Color=16711680
|RECORD=13|OwnerIndex=791|IsNotAccesible=T|IndexInSheet=58|OwnerPartId=1|Location.X=922|Location.Y=350|Corner.X=909|Corner.X_Frac=50000|Corner.Y=350|LineWidth=1|Color=16711680
|RECORD=14|OwnerIndex=791|IsNotAccesible=T|IndexInSheet=59|OwnerPartId=1|Location.X=910|Location.Y=340|Corner.X=950|Corner.Y=400|Color=128|AreaColor=11599871|IsSolid=T|Transparent=T
|RECORD=34|OwnerIndex=791|IndexInSheet=-1|OwnerPartId=-1|Location.X=908|Location.X_Frac=50000|Location.Y=400|Color=8388608|FontID=3|Text=U5|Name=Designator|ReadOnlyState=1
|RECORD=41|OwnerIndex=791|IndexInSheet=-1|OwnerPartId=-1|Location.X=910|Location.Y=310|Color=8388608|FontID=2|IsHidden=T|Text==MFG PART NUM|Name=Comment
|RECORD=44|OwnerIndex=791
|RECORD=45|OwnerIndex=864|IndexInSheet=-1|UseComponentLibrary=T|ModelName=SAMTEC_HTST-105-01-L-DV-A|ModelType=PCBLIB|DatafileCount=1|ModelDatafileEntity0=SAMTEC_HTST-105-01-L-DV-A|ModelDatafileKind0=PCBLib|IsCurrent=T|DatalinksLocked=T|DatabaseDatalinksLocked=T|IntegratedModel=T|DatabaseModel=T
|RECORD=46|OwnerIndex=865
|RECORD=48|OwnerIndex=865
|RECORD=1|LibReference=BAT54SW|ComponentDescription=DIO, SCHOTTKY, BAT54S, DUAL SERIES, 30V, 200MA, SC-70|PartCount=2|DisplayModeCount=1|IndexInSheet=96|OwnerPartId=-1|Location.X=1020|Location.Y=180|Orientation=1|CurrentPartId=1|LibraryPath=*|SourceLibraryName=Passives.IntLib|TargetFileName=*|AreaColor=11599871|Color=128|PartIDLocked=F|DesignItemId=BAT54SW|AllPinCount=3
|RECORD=41|OwnerIndex=868|OwnerPartId=-1|Location.X=1009|Location.Y=252|Color=8388608|FontID=2|IsHidden=T|Text=BAT54SWQ-7-F|Name=MFG PART NUM
|RECORD=41|OwnerIndex=868|IndexInSheet=1|OwnerPartId=-1|Location.X=1009|Location.Y=252|Color=8388608|FontID=2|IsHidden=T|Text=9/4/2013|Name=MODIFY DATE
|RECORD=41|OwnerIndex=868|IndexInSheet=2|OwnerPartId=-1|Location.X=1009|Location.Y=252|Color=8388608|FontID=2|IsHidden=T|Text=DIODES INC|Name=MFG NAME
|RECORD=41|OwnerIndex=868|IndexInSheet=3|OwnerPartId=-1|Location.X=1009|Location.Y=252|Color=8388608|FontID=2|IsHidden=T|Text=DIO, SCHOTTKY|Name=CATEGORY
|RECORD=41|OwnerIndex=868|IndexInSheet=4|OwnerPartId=-1|Location.X=1009|Location.Y=252|Color=8388608|FontID=2|IsHidden=T|Name=DATE
|RECORD=41|OwnerIndex=868|IndexInSheet=5|OwnerPartId=-1|Location.X=1009|Location.Y=252|Color=8388608|FontID=2|IsHidden=T|Text=150C|Name=MAXTEMP
|RECORD=41|OwnerIndex=868|IndexInSheet=6|OwnerPartId=-1|Location.X=1009|Location.Y=252|Color=8388608|FontID=2|IsHidden=T|Text=-55C|Name=MINTEMP
|RECORD=41|OwnerIndex=868|IndexInSheet=7|OwnerPartId=-1|Location.X=1009|Location.Y=252|Color=8388608|FontID=2|IsHidden=T|Text=SERIES|Name=OTHER
|RECORD=41|OwnerIndex=868|IndexInSheet=8|OwnerPartId=-1|Location.X=1009|Location.Y=252|Color=8388608|FontID=2|IsHidden=T|Text=SCHOTTKY|Name=P1
|RECORD=41|OwnerIndex=868|IndexInSheet=9|OwnerPartId=-1|Location.X=1009|Location.Y=252|Color=8388608|FontID=2|IsHidden=T|Text=30V|Name=P2
|RECORD=41|OwnerIndex=868|IndexInSheet=10|OwnerPartId=-1|Location.X=1009|Location.Y=252|Color=8388608|FontID=2|IsHidden=T|Text=200mA,200mW|Name=P3
|RECORD=41|OwnerIndex=868|IndexInSheet=11|OwnerPartId=-1|Location.X=1009|Location.Y=252|Color=8388608|FontID=2|IsHidden=T|Text=SC-70|Name=SIZE
|RECORD=41|OwnerIndex=868|IndexInSheet=12|OwnerPartId=-1|Location.X=1009|Location.Y=252|Color=8388608|FontID=2|IsHidden=T|Name=SUB
|RECORD=41|OwnerIndex=868|IndexInSheet=13|OwnerPartId=-1|Location.X=1009|Location.Y=252|Color=8388608|FontID=1|IsHidden=T|Text=*|Name=SHEETPART
|RECORD=41|OwnerIndex=868|IndexInSheet=14|OwnerPartId=-1|Location.X=1009|Location.Y=252|Color=8388608|FontID=1|IsHidden=T|Text=DIO, SCHOTTKY, BAT54S, DUAL SERIES, 30V, 200MA, SC-70|Name=DESC
|RECORD=41|OwnerIndex=868|IndexInSheet=15|OwnerPartId=-1|Location.X=1009|Location.Y=252|Color=8388608|FontID=1|IsHidden=T|Text=Digi-Key|Name=Supplier 1|ReadOnlyState=3
|RECORD=41|OwnerIndex=868|IndexInSheet=16|OwnerPartId=-1|Location.X=1009|Location.Y=252|Color=8388608|FontID=1|IsHidden=T|Text=BAT54SWQ-7-FDICT-ND|Name=Supplier Part Number 1|ReadOnlyState=3
|RECORD=41|OwnerIndex=868|IndexInSheet=17|OwnerPartId=-1|Location.X=1051|Location.Y=205|Color=8388608|FontID=2|Text=BAT54SW|Name=VALUE
|RECORD=2|OwnerIndex=868|OwnerPartId=1|FormalType=1|Electrical=4|PinConglomerate=51|PinLength=20|Location.X=1040|Location.Y=200|Name=2|Designator=2|SwapIdPin=1|SwapIDPart=1|PinPropagationDelay=0.000000E+000
|RECORD=2|OwnerIndex=868|OwnerPartId=1|FormalType=1|Electrical=4|PinConglomerate=49|PinLength=20|Location.X=1030|Location.Y=230|Name=3|Designator=3|SwapIdPin=2|SwapIDPart=1|PinPropagationDelay=0.000000E+000
|RECORD=2|OwnerIndex=868|OwnerPartId=1|FormalType=1|Electrical=4|PinConglomerate=51|PinLength=20|Location.X=1020|Location.Y=200|Name=1|Designator=1|SwapIdPin=3|SwapIDPart=1|PinPropagationDelay=0.000000E+000
|RECORD=13|OwnerIndex=868|IsNotAccesible=T|IndexInSheet=21|OwnerPartId=1|Location.X=1020|Location.Y=230|Corner.X=1020|Corner.Y=220|LineWidth=1|Color=16711680
|RECORD=13|OwnerIndex=868|IsNotAccesible=T|IndexInSheet=22|OwnerPartId=1|Location.X=1030|Location.Y=208|Corner.X=1050|Corner.Y=208|LineWidth=1|Color=16711680
|RECORD=13|OwnerIndex=868|IsNotAccesible=T|IndexInSheet=23|OwnerPartId=1|Location.X=1040|Location.Y=210|Corner.X=1040|Corner.Y=200|LineWidth=1|Color=16711680
|RECORD=13|OwnerIndex=868|IsNotAccesible=T|IndexInSheet=24|OwnerPartId=1|Location.X=1040|Location.Y=230|Corner.X=1040|Corner.Y=220|LineWidth=1|Color=16711680
|RECORD=13|OwnerIndex=868|IsNotAccesible=T|IndexInSheet=25|OwnerPartId=1|Location.X=1020|Location.Y=210|Corner.X=1020|Corner.Y=200|LineWidth=1|Color=16711680
|RECORD=13|OwnerIndex=868|IsNotAccesible=T|IndexInSheet=26|OwnerPartId=1|Location.X=1010|Location.Y=220|Corner.X=1030|Corner.Y=220|LineWidth=1|Color=16711680
|RECORD=7|OwnerIndex=868|IsNotAccesible=T|IndexInSheet=27|OwnerPartId=1|LineWidth=1|Color=16711680|AreaColor=16711680|IsSolid=T|LocationCount=3|X1=1020|Y1=220|Y1_Frac=20000|X2=1012|X2_Frac=50000|Y2=207|Y2_Frac=70000|X3=1027|X3_Frac=50000|Y3=207|Y3_Frac=70000
|RECORD=7|OwnerIndex=868|IsNotAccesible=T|IndexInSheet=28|OwnerPartId=1|LineWidth=1|Color=16711680|AreaColor=16711680|IsSolid=T|LocationCount=3|X1=1040|Y1=208|X2=1047|X2_Frac=50000|Y2=220|Y2_Frac=50000|X3=1032|X3_Frac=50000|Y3=220|Y3_Frac=50000
|RECORD=6|OwnerIndex=868|IsNotAccesible=T|IndexInSheet=29|OwnerPartId=1|LineWidth=1|Color=16711680|LocationCount=2|X1=1020|Y1=230|X2=1040|Y2=230
|RECORD=41|OwnerIndex=868|IndexInSheet=30|OwnerPartId=-1|Location.X=1009|Location.Y=252|Color=8388608|FontID=1|IsHidden=T|Text=<VALENTIUM>|Name=VALENTIUM PART NUM
|RECORD=34|OwnerIndex=868|IndexInSheet=-1|OwnerPartId=-1|Location.X=1051|Location.Y=217|Color=8388608|FontID=3|Text=D8|Name=Designator|ReadOnlyState=1
|RECORD=41|OwnerIndex=868|IndexInSheet=-1|OwnerPartId=-1|Location.X=1009|Location.Y=252|Color=8388608|FontID=2|IsHidden=T|Text=BAT54SW|Name=Comment
|RECORD=44|OwnerIndex=868
|RECORD=45|OwnerIndex=905|IndexInSheet=-1|Description=SOT323-3 (SC70), 3-Leads, Body 2.00x2.10mm, Pitch 0.65mm, IPC Medium Density|UseComponentLibrary=T|ModelName=SOT65P210X110-3N|ModelType=PCBLIB|DatafileCount=1|ModelDatafileEntity0=SOT65P210X110-3N|ModelDatafileKind0=PCBLib|IsCurrent=T|DatalinksLocked=T|DatabaseDatalinksLocked=T|IntegratedModel=T|DatabaseModel=T
|RECORD=46|OwnerIndex=906
|RECORD=48|OwnerIndex=906
|RECORD=1|LibReference=BAT54SW|ComponentDescription=DIO, SCHOTTKY, BAT54S, DUAL SERIES, 30V, 200MA, SC-70|PartCount=2|DisplayModeCount=1|IndexInSheet=97|OwnerPartId=-1|Location.X=880|Location.Y=180|Orientation=1|CurrentPartId=1|LibraryPath=*|SourceLibraryName=Passives.IntLib|TargetFileName=*|AreaColor=11599871|Color=128|PartIDLocked=F|DesignItemId=BAT54SW|AllPinCount=3
|RECORD=41|OwnerIndex=909|OwnerPartId=-1|Location.X=869|Location.Y=252|Color=8388608|FontID=2|IsHidden=T|Text=BAT54SWQ-7-F|Name=MFG PART NUM
|RECORD=41|OwnerIndex=909|IndexInSheet=1|OwnerPartId=-1|Location.X=869|Location.Y=252|Color=8388608|FontID=2|IsHidden=T|Text=9/4/2013|Name=MODIFY DATE
|RECORD=41|OwnerIndex=909|IndexInSheet=2|OwnerPartId=-1|Location.X=869|Location.Y=252|Color=8388608|FontID=2|IsHidden=T|Text=DIODES INC|Name=MFG NAME
|RECORD=41|OwnerIndex=909|IndexInSheet=3|OwnerPartId=-1|Location.X=869|Location.Y=252|Color=8388608|FontID=2|IsHidden=T|Text=DIO, SCHOTTKY|Name=CATEGORY
|RECORD=41|OwnerIndex=909|IndexInSheet=4|OwnerPartId=-1|Location.X=869|Location.Y=252|Color=8388608|FontID=2|IsHidden=T|Name=DATE
|RECORD=41|OwnerIndex=909|IndexInSheet=5|OwnerPartId=-1|Location.X=869|Location.Y=252|Color=8388608|FontID=2|IsHidden=T|Text=150C|Name=MAXTEMP
|RECORD=41|OwnerIndex=909|IndexInSheet=6|OwnerPartId=-1|Location.X=869|Location.Y=252|Color=8388608|FontID=2|IsHidden=T|Text=-55C|Name=MINTEMP
|RECORD=41|OwnerIndex=909|IndexInSheet=7|OwnerPartId=-1|Location.X=869|Location.Y=252|Color=8388608|FontID=2|IsHidden=T|Text=SERIES|Name=OTHER
|RECORD=41|OwnerIndex=909|IndexInSheet=8|OwnerPartId=-1|Location.X=869|Location.Y=252|Color=8388608|FontID=2|IsHidden=T|Text=SCHOTTKY|Name=P1
|RECORD=41|OwnerIndex=909|IndexInSheet=9|OwnerPartId=-1|Location.X=869|Location.Y=252|Color=8388608|FontID=2|IsHidden=T|Text=30V|Name=P2
|RECORD=41|OwnerIndex=909|IndexInSheet=10|OwnerPartId=-1|Location.X=869|Location.Y=252|Color=8388608|FontID=2|IsHidden=T|Text=200mA,200mW|Name=P3
|RECORD=41|OwnerIndex=909|IndexInSheet=11|OwnerPartId=-1|Location.X=869|Location.Y=252|Color=8388608|FontID=2|IsHidden=T|Text=SC-70|Name=SIZE
|RECORD=41|OwnerIndex=909|IndexInSheet=12|OwnerPartId=-1|Location.X=869|Location.Y=252|Color=8388608|FontID=2|IsHidden=T|Name=SUB
|RECORD=41|OwnerIndex=909|IndexInSheet=13|OwnerPartId=-1|Location.X=869|Location.Y=252|Color=8388608|FontID=1|IsHidden=T|Text=*|Name=SHEETPART
|RECORD=41|OwnerIndex=909|IndexInSheet=14|OwnerPartId=-1|Location.X=869|Location.Y=252|Color=8388608|FontID=1|IsHidden=T|Text=DIO, SCHOTTKY, BAT54S, DUAL SERIES, 30V, 200MA, SC-70|Name=DESC
|RECORD=41|OwnerIndex=909|IndexInSheet=15|OwnerPartId=-1|Location.X=869|Location.Y=252|Color=8388608|FontID=1|IsHidden=T|Text=Digi-Key|Name=Supplier 1|ReadOnlyState=3
|RECORD=41|OwnerIndex=909|IndexInSheet=16|OwnerPartId=-1|Location.X=869|Location.Y=252|Color=8388608|FontID=1|IsHidden=T|Text=BAT54SWQ-7-FDICT-ND|Name=Supplier Part Number 1|ReadOnlyState=3
|RECORD=41|OwnerIndex=909|IndexInSheet=17|OwnerPartId=-1|Location.X=911|Location.Y=205|Color=8388608|FontID=2|Text=BAT54SW|Name=VALUE
|RECORD=2|OwnerIndex=909|OwnerPartId=1|FormalType=1|Electrical=4|PinConglomerate=51|PinLength=20|Location.X=900|Location.Y=200|Name=2|Designator=2|SwapIdPin=1|SwapIDPart=1|PinPropagationDelay=0.000000E+000
|RECORD=2|OwnerIndex=909|OwnerPartId=1|FormalType=1|Electrical=4|PinConglomerate=49|PinLength=20|Location.X=890|Location.Y=230|Name=3|Designator=3|SwapIdPin=2|SwapIDPart=1|PinPropagationDelay=0.000000E+000
|RECORD=2|OwnerIndex=909|OwnerPartId=1|FormalType=1|Electrical=4|PinConglomerate=51|PinLength=20|Location.X=880|Location.Y=200|Name=1|Designator=1|SwapIdPin=3|SwapIDPart=1|PinPropagationDelay=0.000000E+000
|RECORD=13|OwnerIndex=909|IsNotAccesible=T|IndexInSheet=21|OwnerPartId=1|Location.X=880|Location.Y=230|Corner.X=880|Corner.Y=220|LineWidth=1|Color=16711680
|RECORD=13|OwnerIndex=909|IsNotAccesible=T|IndexInSheet=22|OwnerPartId=1|Location.X=890|Location.Y=208|Corner.X=910|Corner.Y=208|LineWidth=1|Color=16711680
|RECORD=13|OwnerIndex=909|IsNotAccesible=T|IndexInSheet=23|OwnerPartId=1|Location.X=900|Location.Y=210|Corner.X=900|Corner.Y=200|LineWidth=1|Color=16711680
|RECORD=13|OwnerIndex=909|IsNotAccesible=T|IndexInSheet=24|OwnerPartId=1|Location.X=900|Location.Y=230|Corner.X=900|Corner.Y=220|LineWidth=1|Color=16711680
|RECORD=13|OwnerIndex=909|IsNotAccesible=T|IndexInSheet=25|OwnerPartId=1|Location.X=880|Location.Y=210|Corner.X=880|Corner.Y=200|LineWidth=1|Color=16711680
|RECORD=13|OwnerIndex=909|IsNotAccesible=T|IndexInSheet=26|OwnerPartId=1|Location.X=870|Location.Y=220|Corner.X=890|Corner.Y=220|LineWidth=1|Color=16711680
|RECORD=7|OwnerIndex=909|IsNotAccesible=T|IndexInSheet=27|OwnerPartId=1|LineWidth=1|Color=16711680|AreaColor=16711680|IsSolid=T|LocationCount=3|X1=880|Y1=220|Y1_Frac=20000|X2=872|X2_Frac=50000|Y2=207|Y2_Frac=70000|X3=887|X3_Frac=50000|Y3=207|Y3_Frac=70000
|RECORD=7|OwnerIndex=909|IsNotAccesible=T|IndexInSheet=28|OwnerPartId=1|LineWidth=1|Color=16711680|AreaColor=16711680|IsSolid=T|LocationCount=3|X1=900|Y1=208|X2=907|X2_Frac=50000|Y2=220|Y2_Frac=50000|X3=892|X3_Frac=50000|Y3=220|Y3_Frac=50000
|RECORD=6|OwnerIndex=909|IsNotAccesible=T|IndexInSheet=29|OwnerPartId=1|LineWidth=1|Color=16711680|LocationCount=2|X1=880|Y1=230|X2=900|Y2=230
|RECORD=41|OwnerIndex=909|IndexInSheet=30|OwnerPartId=-1|Location.X=869|Location.Y=252|Color=8388608|FontID=1|IsHidden=T|Text=<VALENTIUM>|Name=VALENTIUM PART NUM
|RECORD=34|OwnerIndex=909|IndexInSheet=-1|OwnerPartId=-1|Location.X=911|Location.Y=217|Color=8388608|FontID=3|Text=D7|Name=Designator|ReadOnlyState=1
|RECORD=41|OwnerIndex=909|IndexInSheet=-1|OwnerPartId=-1|Location.X=869|Location.Y=252|Color=8388608|FontID=2|IsHidden=T|Text=BAT54SW|Name=Comment
|RECORD=44|OwnerIndex=909
|RECORD=45|OwnerIndex=946|IndexInSheet=-1|Description=SOT323-3 (SC70), 3-Leads, Body 2.00x2.10mm, Pitch 0.65mm, IPC Medium Density|UseComponentLibrary=T|ModelName=SOT65P210X110-3N|ModelType=PCBLIB|DatafileCount=1|ModelDatafileEntity0=SOT65P210X110-3N|ModelDatafileKind0=PCBLib|IsCurrent=T|DatalinksLocked=T|DatabaseDatalinksLocked=T|IntegratedModel=T|DatabaseModel=T
|RECORD=46|OwnerIndex=947
|RECORD=48|OwnerIndex=947
|RECORD=1|LibReference=BAT54SW|ComponentDescription=DIO, SCHOTTKY, BAT54S, DUAL SERIES, 30V, 200MA, SC-70|PartCount=2|DisplayModeCount=1|IndexInSheet=98|OwnerPartId=-1|Location.X=740|Location.Y=180|Orientation=1|CurrentPartId=1|LibraryPath=*|SourceLibraryName=Passives.IntLib|TargetFileName=*|AreaColor=11599871|Color=128|PartIDLocked=F|DesignItemId=BAT54SW|AllPinCount=3
|RECORD=41|OwnerIndex=950|OwnerPartId=-1|Location.X=729|Location.Y=252|Color=8388608|FontID=2|IsHidden=T|Text=BAT54SWQ-7-F|Name=MFG PART NUM
|RECORD=41|OwnerIndex=950|IndexInSheet=1|OwnerPartId=-1|Location.X=729|Location.Y=252|Color=8388608|FontID=2|IsHidden=T|Text=9/4/2013|Name=MODIFY DATE
|RECORD=41|OwnerIndex=950|IndexInSheet=2|OwnerPartId=-1|Location.X=729|Location.Y=252|Color=8388608|FontID=2|IsHidden=T|Text=DIODES INC|Name=MFG NAME
|RECORD=41|OwnerIndex=950|IndexInSheet=3|OwnerPartId=-1|Location.X=729|Location.Y=252|Color=8388608|FontID=2|IsHidden=T|Text=DIO, SCHOTTKY|Name=CATEGORY
|RECORD=41|OwnerIndex=950|IndexInSheet=4|OwnerPartId=-1|Location.X=729|Location.Y=252|Color=8388608|FontID=2|IsHidden=T|Name=DATE
|RECORD=41|OwnerIndex=950|IndexInSheet=5|OwnerPartId=-1|Location.X=729|Location.Y=252|Color=8388608|FontID=2|IsHidden=T|Text=150C|Name=MAXTEMP
|RECORD=41|OwnerIndex=950|IndexInSheet=6|OwnerPartId=-1|Location.X=729|Location.Y=252|Color=8388608|FontID=2|IsHidden=T|Text=-55C|Name=MINTEMP
|RECORD=41|OwnerIndex=950|IndexInSheet=7|OwnerPartId=-1|Location.X=729|Location.Y=252|Color=8388608|FontID=2|IsHidden=T|Text=SERIES|Name=OTHER
|RECORD=41|OwnerIndex=950|IndexInSheet=8|OwnerPartId=-1|Location.X=729|Location.Y=252|Color=8388608|FontID=2|IsHidden=T|Text=SCHOTTKY|Name=P1
|RECORD=41|OwnerIndex=950|IndexInSheet=9|OwnerPartId=-1|Location.X=729|Location.Y=252|Color=8388608|FontID=2|IsHidden=T|Text=30V|Name=P2
|RECORD=41|OwnerIndex=950|IndexInSheet=10|OwnerPartId=-1|Location.X=729|Location.Y=252|Color=8388608|FontID=2|IsHidden=T|Text=200mA,200mW|Name=P3
|RECORD=41|OwnerIndex=950|IndexInSheet=11|OwnerPartId=-1|Location.X=729|Location.Y=252|Color=8388608|FontID=2|IsHidden=T|Text=SC-70|Name=SIZE
|RECORD=41|OwnerIndex=950|IndexInSheet=12|OwnerPartId=-1|Location.X=729|Location.Y=252|Color=8388608|FontID=2|IsHidden=T|Name=SUB
|RECORD=41|OwnerIndex=950|IndexInSheet=13|OwnerPartId=-1|Location.X=729|Location.Y=252|Color=8388608|FontID=1|IsHidden=T|Text=*|Name=SHEETPART
|RECORD=41|OwnerIndex=950|IndexInSheet=14|OwnerPartId=-1|Location.X=729|Location.Y=252|Color=8388608|FontID=1|IsHidden=T|Text=DIO, SCHOTTKY, BAT54S, DUAL SERIES, 30V, 200MA, SC-70|Name=DESC
|RECORD=41|OwnerIndex=950|IndexInSheet=15|OwnerPartId=-1|Location.X=729|Location.Y=252|Color=8388608|FontID=1|IsHidden=T|Text=Digi-Key|Name=Supplier 1|ReadOnlyState=3
|RECORD=41|OwnerIndex=950|IndexInSheet=16|OwnerPartId=-1|Location.X=729|Location.Y=252|Color=8388608|FontID=1|IsHidden=T|Text=BAT54SWQ-7-FDICT-ND|Name=Supplier Part Number 1|ReadOnlyState=3
|RECORD=41|OwnerIndex=950|IndexInSheet=17|OwnerPartId=-1|Location.X=771|Location.Y=205|Color=8388608|FontID=2|Text=BAT54SW|Name=VALUE
|RECORD=2|OwnerIndex=950|OwnerPartId=1|FormalType=1|Electrical=4|PinConglomerate=51|PinLength=20|Location.X=760|Location.Y=200|Name=2|Designator=2|SwapIdPin=1|SwapIDPart=1|PinPropagationDelay=0.000000E+000
|RECORD=2|OwnerIndex=950|OwnerPartId=1|FormalType=1|Electrical=4|PinConglomerate=49|PinLength=20|Location.X=750|Location.Y=230|Name=3|Designator=3|SwapIdPin=2|SwapIDPart=1|PinPropagationDelay=0.000000E+000
|RECORD=2|OwnerIndex=950|OwnerPartId=1|FormalType=1|Electrical=4|PinConglomerate=51|PinLength=20|Location.X=740|Location.Y=200|Name=1|Designator=1|SwapIdPin=3|SwapIDPart=1|PinPropagationDelay=0.000000E+000
|RECORD=13|OwnerIndex=950|IsNotAccesible=T|IndexInSheet=21|OwnerPartId=1|Location.X=740|Location.Y=230|Corner.X=740|Corner.Y=220|LineWidth=1|Color=16711680
|RECORD=13|OwnerIndex=950|IsNotAccesible=T|IndexInSheet=22|OwnerPartId=1|Location.X=750|Location.Y=208|Corner.X=770|Corner.Y=208|LineWidth=1|Color=16711680
|RECORD=13|OwnerIndex=950|IsNotAccesible=T|IndexInSheet=23|OwnerPartId=1|Location.X=760|Location.Y=210|Corner.X=760|Corner.Y=200|LineWidth=1|Color=16711680
|RECORD=13|OwnerIndex=950|IsNotAccesible=T|IndexInSheet=24|OwnerPartId=1|Location.X=760|Location.Y=230|Corner.X=760|Corner.Y=220|LineWidth=1|Color=16711680
|RECORD=13|OwnerIndex=950|IsNotAccesible=T|IndexInSheet=25|OwnerPartId=1|Location.X=740|Location.Y=210|Corner.X=740|Corner.Y=200|LineWidth=1|Color=16711680
|RECORD=13|OwnerIndex=950|IsNotAccesible=T|IndexInSheet=26|OwnerPartId=1|Location.X=730|Location.Y=220|Corner.X=750|Corner.Y=220|LineWidth=1|Color=16711680
|RECORD=7|OwnerIndex=950|IsNotAccesible=T|IndexInSheet=27|OwnerPartId=1|LineWidth=1|Color=16711680|AreaColor=16711680|IsSolid=T|LocationCount=3|X1=740|Y1=220|Y1_Frac=20000|X2=732|X2_Frac=50000|Y2=207|Y2_Frac=70000|X3=747|X3_Frac=50000|Y3=207|Y3_Frac=70000
|RECORD=7|OwnerIndex=950|IsNotAccesible=T|IndexInSheet=28|OwnerPartId=1|LineWidth=1|Color=16711680|AreaColor=16711680|IsSolid=T|LocationCount=3|X1=760|Y1=208|X2=767|X2_Frac=50000|Y2=220|Y2_Frac=50000|X3=752|X3_Frac=50000|Y3=220|Y3_Frac=50000
|RECORD=6|OwnerIndex=950|IsNotAccesible=T|IndexInSheet=29|OwnerPartId=1|LineWidth=1|Color=16711680|LocationCount=2|X1=740|Y1=230|X2=760|Y2=230
|RECORD=41|OwnerIndex=950|IndexInSheet=30|OwnerPartId=-1|Location.X=729|Location.Y=252|Color=8388608|FontID=1|IsHidden=T|Text=<VALENTIUM>|Name=VALENTIUM PART NUM
|RECORD=34|OwnerIndex=950|IndexInSheet=-1|OwnerPartId=-1|Location.X=771|Location.Y=217|Color=8388608|FontID=3|Text=D6|Name=Designator|ReadOnlyState=1
|RECORD=41|OwnerIndex=950|IndexInSheet=-1|OwnerPartId=-1|Location.X=729|Location.Y=252|Color=8388608|FontID=2|IsHidden=T|Text=BAT54SW|Name=Comment
|RECORD=44|OwnerIndex=950
|RECORD=45|OwnerIndex=987|IndexInSheet=-1|Description=SOT323-3 (SC70), 3-Leads, Body 2.00x2.10mm, Pitch 0.65mm, IPC Medium Density|UseComponentLibrary=T|ModelName=SOT65P210X110-3N|ModelType=PCBLIB|DatafileCount=1|ModelDatafileEntity0=SOT65P210X110-3N|ModelDatafileKind0=PCBLib|IsCurrent=T|DatalinksLocked=T|DatabaseDatalinksLocked=T|IntegratedModel=T|DatabaseModel=T
|RECORD=46|OwnerIndex=988
|RECORD=48|OwnerIndex=988
|RECORD=1|LibReference=BAT54SW|ComponentDescription=DIO, SCHOTTKY, BAT54S, DUAL SERIES, 30V, 200MA, SC-70|PartCount=2|DisplayModeCount=1|IndexInSheet=99|OwnerPartId=-1|Location.X=600|Location.Y=180|Orientation=1|CurrentPartId=1|LibraryPath=*|SourceLibraryName=Passives.IntLib|TargetFileName=*|AreaColor=11599871|Color=128|PartIDLocked=F|DesignItemId=BAT54SW|AllPinCount=3
|RECORD=41|OwnerIndex=991|OwnerPartId=-1|Location.X=589|Location.Y=252|Color=8388608|FontID=2|IsHidden=T|Text=BAT54SWQ-7-F|Name=MFG PART NUM
|RECORD=41|OwnerIndex=991|IndexInSheet=1|OwnerPartId=-1|Location.X=589|Location.Y=252|Color=8388608|FontID=2|IsHidden=T|Text=9/4/2013|Name=MODIFY DATE
|RECORD=41|OwnerIndex=991|IndexInSheet=2|OwnerPartId=-1|Location.X=589|Location.Y=252|Color=8388608|FontID=2|IsHidden=T|Text=DIODES INC|Name=MFG NAME
|RECORD=41|OwnerIndex=991|IndexInSheet=3|OwnerPartId=-1|Location.X=589|Location.Y=252|Color=8388608|FontID=2|IsHidden=T|Text=DIO, SCHOTTKY|Name=CATEGORY
|RECORD=41|OwnerIndex=991|IndexInSheet=4|OwnerPartId=-1|Location.X=589|Location.Y=252|Color=8388608|FontID=2|IsHidden=T|Name=DATE
|RECORD=41|OwnerIndex=991|IndexInSheet=5|OwnerPartId=-1|Location.X=589|Location.Y=252|Color=8388608|FontID=2|IsHidden=T|Text=150C|Name=MAXTEMP
|RECORD=41|OwnerIndex=991|IndexInSheet=6|OwnerPartId=-1|Location.X=589|Location.Y=252|Color=8388608|FontID=2|IsHidden=T|Text=-55C|Name=MINTEMP
|RECORD=41|OwnerIndex=991|IndexInSheet=7|OwnerPartId=-1|Location.X=589|Location.Y=252|Color=8388608|FontID=2|IsHidden=T|Text=SERIES|Name=OTHER
|RECORD=41|OwnerIndex=991|IndexInSheet=8|OwnerPartId=-1|Location.X=589|Location.Y=252|Color=8388608|FontID=2|IsHidden=T|Text=SCHOTTKY|Name=P1
|RECORD=41|OwnerIndex=991|IndexInSheet=9|OwnerPartId=-1|Location.X=589|Location.Y=252|Color=8388608|FontID=2|IsHidden=T|Text=30V|Name=P2
|RECORD=41|OwnerIndex=991|IndexInSheet=10|OwnerPartId=-1|Location.X=589|Location.Y=252|Color=8388608|FontID=2|IsHidden=T|Text=200mA,200mW|Name=P3
|RECORD=41|OwnerIndex=991|IndexInSheet=11|OwnerPartId=-1|Location.X=589|Location.Y=252|Color=8388608|FontID=2|IsHidden=T|Text=SC-70|Name=SIZE
|RECORD=41|OwnerIndex=991|IndexInSheet=12|OwnerPartId=-1|Location.X=589|Location.Y=252|Color=8388608|FontID=2|IsHidden=T|Name=SUB
|RECORD=41|OwnerIndex=991|IndexInSheet=13|OwnerPartId=-1|Location.X=589|Location.Y=252|Color=8388608|FontID=1|IsHidden=T|Text=*|Name=SHEETPART
|RECORD=41|OwnerIndex=991|IndexInSheet=14|OwnerPartId=-1|Location.X=589|Location.Y=252|Color=8388608|FontID=1|IsHidden=T|Text=DIO, SCHOTTKY, BAT54S, DUAL SERIES, 30V, 200MA, SC-70|Name=DESC
|RECORD=41|OwnerIndex=991|IndexInSheet=15|OwnerPartId=-1|Location.X=589|Location.Y=252|Color=8388608|FontID=1|IsHidden=T|Text=Digi-Key|Name=Supplier 1|ReadOnlyState=3
|RECORD=41|OwnerIndex=991|IndexInSheet=16|OwnerPartId=-1|Location.X=589|Location.Y=252|Color=8388608|FontID=1|IsHidden=T|Text=BAT54SWQ-7-FDICT-ND|Name=Supplier Part Number 1|ReadOnlyState=3
|RECORD=41|OwnerIndex=991|IndexInSheet=17|OwnerPartId=-1|Location.X=631|Location.Y=205|Color=8388608|FontID=2|Text=BAT54SW|Name=VALUE
|RECORD=2|OwnerIndex=991|OwnerPartId=1|FormalType=1|Electrical=4|PinConglomerate=51|PinLength=20|Location.X=620|Location.Y=200|Name=2|Designator=2|SwapIdPin=1|SwapIDPart=1|PinPropagationDelay=0.000000E+000
|RECORD=2|OwnerIndex=991|OwnerPartId=1|FormalType=1|Electrical=4|PinConglomerate=49|PinLength=20|Location.X=610|Location.Y=230|Name=3|Designator=3|SwapIdPin=2|SwapIDPart=1|PinPropagationDelay=0.000000E+000
|RECORD=2|OwnerIndex=991|OwnerPartId=1|FormalType=1|Electrical=4|PinConglomerate=51|PinLength=20|Location.X=600|Location.Y=200|Name=1|Designator=1|SwapIdPin=3|SwapIDPart=1|PinPropagationDelay=0.000000E+000
|RECORD=13|OwnerIndex=991|IsNotAccesible=T|IndexInSheet=21|OwnerPartId=1|Location.X=600|Location.Y=230|Corner.X=600|Corner.Y=220|LineWidth=1|Color=16711680
|RECORD=13|OwnerIndex=991|IsNotAccesible=T|IndexInSheet=22|OwnerPartId=1|Location.X=610|Location.Y=208|Corner.X=630|Corner.Y=208|LineWidth=1|Color=16711680
|RECORD=13|OwnerIndex=991|IsNotAccesible=T|IndexInSheet=23|OwnerPartId=1|Location.X=620|Location.Y=210|Corner.X=620|Corner.Y=200|LineWidth=1|Color=16711680
|RECORD=13|OwnerIndex=991|IsNotAccesible=T|IndexInSheet=24|OwnerPartId=1|Location.X=620|Location.Y=230|Corner.X=620|Corner.Y=220|LineWidth=1|Color=16711680
|RECORD=13|OwnerIndex=991|IsNotAccesible=T|IndexInSheet=25|OwnerPartId=1|Location.X=600|Location.Y=210|Corner.X=600|Corner.Y=200|LineWidth=1|Color=16711680
|RECORD=13|OwnerIndex=991|IsNotAccesible=T|IndexInSheet=26|OwnerPartId=1|Location.X=590|Location.Y=220|Corner.X=610|Corner.Y=220|LineWidth=1|Color=16711680
|RECORD=7|OwnerIndex=991|IsNotAccesible=T|IndexInSheet=27|OwnerPartId=1|LineWidth=1|Color=16711680|AreaColor=16711680|IsSolid=T|LocationCount=3|X1=600|Y1=220|Y1_Frac=20000|X2=592|X2_Frac=50000|Y2=207|Y2_Frac=70000|X3=607|X3_Frac=50000|Y3=207|Y3_Frac=70000
|RECORD=7|OwnerIndex=991|IsNotAccesible=T|IndexInSheet=28|OwnerPartId=1|LineWidth=1|Color=16711680|AreaColor=16711680|IsSolid=T|LocationCount=3|X1=620|Y1=208|X2=627|X2_Frac=50000|Y2=220|Y2_Frac=50000|X3=612|X3_Frac=50000|Y3=220|Y3_Frac=50000
|RECORD=6|OwnerIndex=991|IsNotAccesible=T|IndexInSheet=29|OwnerPartId=1|LineWidth=1|Color=16711680|LocationCount=2|X1=600|Y1=230|X2=620|Y2=230
|RECORD=41|OwnerIndex=991|IndexInSheet=30|OwnerPartId=-1|Location.X=589|Location.Y=252|Color=8388608|FontID=1|IsHidden=T|Text=<VALENTIUM>|Name=VALENTIUM PART NUM
|RECORD=34|OwnerIndex=991|IndexInSheet=-1|OwnerPartId=-1|Location.X=631|Location.Y=217|Color=8388608|FontID=3|Text=D5|Name=Designator|ReadOnlyState=1
|RECORD=41|OwnerIndex=991|IndexInSheet=-1|OwnerPartId=-1|Location.X=589|Location.Y=252|Color=8388608|FontID=2|IsHidden=T|Text=BAT54SW|Name=Comment
|RECORD=44|OwnerIndex=991
|RECORD=45|OwnerIndex=1028|IndexInSheet=-1|Description=SOT323-3 (SC70), 3-Leads, Body 2.00x2.10mm, Pitch 0.65mm, IPC Medium Density|UseComponentLibrary=T|ModelName=SOT65P210X110-3N|ModelType=PCBLIB|DatafileCount=1|ModelDatafileEntity0=SOT65P210X110-3N|ModelDatafileKind0=PCBLib|IsCurrent=T|DatalinksLocked=T|DatabaseDatalinksLocked=T|IntegratedModel=T|DatabaseModel=T
|RECORD=46|OwnerIndex=1029
|RECORD=48|OwnerIndex=1029
|RECORD=25|IndexInSheet=100|OwnerPartId=-1|Location.X=940|Location.Y=950|Color=128|FontID=1|Text=PRSNT
|RECORD=25|IndexInSheet=101|OwnerPartId=-1|Location.X=600|Location.Y=780|Color=128|FontID=1|Text=PRSNT
|RECORD=25|IndexInSheet=102|OwnerPartId=-1|Location.X=600|Location.Y=640|Color=128|FontID=1|Text=PRSNT
|RECORD=17|IndexInSheet=103|OwnerPartId=-1|ShowNetName=T|Location.X=620|Location.Y=260|Color=255|FontID=1|Text=FPGA_TCK|IsCrossSheetConnector=T
|RECORD=17|IndexInSheet=104|OwnerPartId=-1|ShowNetName=T|Location.X=760|Location.Y=260|Color=255|FontID=1|Text=FPGA_TDO|IsCrossSheetConnector=T
|RECORD=17|IndexInSheet=105|OwnerPartId=-1|ShowNetName=T|Location.X=900|Location.Y=260|Color=255|FontID=1|Text=FPGA_TMS|IsCrossSheetConnector=T
|RECORD=17|IndexInSheet=106|OwnerPartId=-1|ShowNetName=T|Location.X=1040|Location.Y=260|Color=255|FontID=1|Text=FPGA_TDI|IsCrossSheetConnector=T
|RECORD=27|IndexInSheet=107|OwnerPartId=-1|LineWidth=1|Color=8388608|LocationCount=2|X1=740|Y1=690|X2=740|Y2=700
|RECORD=27|IndexInSheet=108|OwnerPartId=-1|LineWidth=1|Color=8388608|LocationCount=2|X1=760|Y1=670|X2=540|Y2=670
|RECORD=27|IndexInSheet=109|OwnerPartId=-1|LineWidth=1|Color=8388608|LocationCount=2|X1=760|Y1=680|X2=540|Y2=680
|RECORD=27|IndexInSheet=110|OwnerPartId=-1|LineWidth=1|Color=8388608|LocationCount=2|X1=760|Y1=710|X2=540|Y2=710
|RECORD=27|IndexInSheet=111|OwnerPartId=-1|LineWidth=1|Color=8388608|LocationCount=2|X1=760|Y1=720|X2=540|Y2=720
|RECORD=27|IndexInSheet=112|OwnerPartId=-1|LineWidth=1|Color=8388608|LocationCount=2|X1=760|Y1=750|X2=540|Y2=750
|RECORD=27|IndexInSheet=113|OwnerPartId=-1|LineWidth=1|Color=8388608|LocationCount=2|X1=760|Y1=760|X2=540|Y2=760
|RECORD=27|IndexInSheet=114|OwnerPartId=-1|LineWidth=1|Color=8388608|LocationCount=2|X1=760|Y1=800|X2=540|Y2=800
|RECORD=27|IndexInSheet=115|OwnerPartId=-1|LineWidth=1|Color=8388608|LocationCount=2|X1=760|Y1=810|X2=540|Y2=810
|RECORD=27|IndexInSheet=116|OwnerPartId=-1|LineWidth=1|Color=8388608|LocationCount=3|X1=760|Y1=880|X2=540|Y2=880|X3=540|Y3=970
|RECORD=27|IndexInSheet=117|OwnerPartId=-1|LineWidth=1|Color=8388608|LocationCount=2|X1=600|Y1=180|X2=590|Y2=180
|RECORD=27|IndexInSheet=118|OwnerPartId=-1|LineWidth=1|Color=8388608|LocationCount=2|X1=670|Y1=640|X2=590|Y2=640
|RECORD=27|IndexInSheet=119|OwnerPartId=-1|LineWidth=1|Color=8388608|LocationCount=2|X1=670|Y1=780|X2=590|Y2=780
|RECORD=27|IndexInSheet=120|OwnerPartId=-1|LineWidth=1|Color=8388608|LocationCount=3|X1=610|Y1=250|X2=610|Y2=260|X3=620|Y3=260
|RECORD=27|IndexInSheet=121|OwnerPartId=-1|LineWidth=1|Color=8388608|LocationCount=3|X1=630|Y1=170|X2=630|Y2=180|X3=620|Y3=180
|RECORD=27|IndexInSheet=122|OwnerPartId=-1|LineWidth=1|Color=8388608|LocationCount=5|X1=760|Y1=930|X2=670|Y2=930|X3=670|Y3=940|X4=670|Y4=950|X5=670|Y5=970
|RECORD=27|IndexInSheet=123|OwnerPartId=-1|LineWidth=1|Color=8388608|LocationCount=2|X1=760|Y1=940|X2=670|Y2=940
|RECORD=27|IndexInSheet=124|OwnerPartId=-1|LineWidth=1|Color=8388608|LocationCount=2|X1=760|Y1=950|X2=670|Y2=950
|RECORD=27|IndexInSheet=125|OwnerPartId=-1|LineWidth=1|Color=8388608|LocationCount=2|X1=760|Y1=640|X2=720|Y2=640
|RECORD=27|IndexInSheet=126|OwnerPartId=-1|LineWidth=1|Color=8388608|LocationCount=2|X1=760|Y1=780|X2=720|Y2=780
|RECORD=27|IndexInSheet=127|OwnerPartId=-1|LineWidth=1|Color=8388608|LocationCount=2|X1=740|Y1=180|X2=730|Y2=180
|RECORD=27|IndexInSheet=128|OwnerPartId=-1|LineWidth=1|Color=8388608|LocationCount=2|X1=790|Y1=340|X2=730|Y2=340
|RECORD=27|IndexInSheet=129|OwnerPartId=-1|LineWidth=1|Color=8388608|LocationCount=2|X1=790|Y1=370|X2=730|Y2=370
|RECORD=27|IndexInSheet=130|OwnerPartId=-1|LineWidth=1|Color=8388608|LocationCount=2|X1=790|Y1=400|X2=730|Y2=400
|RECORD=27|IndexInSheet=131|OwnerPartId=-1|LineWidth=1|Color=8388608|LocationCount=2|X1=790|Y1=430|X2=730|Y2=430
|RECORD=27|IndexInSheet=132|OwnerPartId=-1|LineWidth=1|Color=8388608|LocationCount=2|X1=760|Y1=630|X2=740|Y2=630
|RECORD=27|IndexInSheet=133|OwnerPartId=-1|LineWidth=1|Color=8388608|LocationCount=2|X1=760|Y1=660|X2=740|Y2=660
|RECORD=27|IndexInSheet=134|OwnerPartId=-1|LineWidth=1|Color=8388608|LocationCount=5|X1=760|Y1=690|X2=740|Y2=690|X3=740|Y3=660|X4=740|Y4=630|X5=740|Y5=600
|RECORD=27|IndexInSheet=135|OwnerPartId=-1|LineWidth=1|Color=8388608|LocationCount=2|X1=760|Y1=700|X2=740|Y2=700
|RECORD=27|IndexInSheet=136|OwnerPartId=-1|LineWidth=1|Color=8388608|LocationCount=2|X1=760|Y1=730|X2=740|Y2=730
|RECORD=27|IndexInSheet=137|OwnerPartId=-1|LineWidth=1|Color=8388608|LocationCount=2|X1=760|Y1=740|X2=740|Y2=740
|RECORD=27|IndexInSheet=138|OwnerPartId=-1|LineWidth=1|Color=8388608|LocationCount=2|X1=760|Y1=770|X2=740|Y2=770
|RECORD=27|IndexInSheet=139|OwnerPartId=-1|LineWidth=1|Color=8388608|LocationCount=2|X1=760|Y1=790|X2=740|Y2=790
|RECORD=27|IndexInSheet=140|OwnerPartId=-1|LineWidth=1|Color=8388608|LocationCount=2|X1=760|Y1=820|X2=740|Y2=820
|RECORD=27|IndexInSheet=141|OwnerPartId=-1|LineWidth=1|Color=8388608|LocationCount=2|X1=760|Y1=890|X2=740|Y2=890
|RECORD=27|IndexInSheet=142|OwnerPartId=-1|LineWidth=1|Color=8388608|LocationCount=9|X1=760|Y1=920|X2=740|Y2=920|X3=740|Y3=890|X4=740|Y4=820|X5=740|Y5=790|X6=740|Y6=770|X7=740|Y7=740|X8=740|Y8=730|X9=740|Y9=700
|RECORD=27|IndexInSheet=143|OwnerPartId=-1|LineWidth=1|Color=8388608|LocationCount=3|X1=750|Y1=250|X2=750|Y2=260|X3=760|Y3=260
|RECORD=27|IndexInSheet=144|OwnerPartId=-1|LineWidth=1|Color=8388608|LocationCount=4|X1=760|Y1=180|X2=760|Y2=179|X3=770|Y3=179|X4=770|Y4=169
|RECORD=27|IndexInSheet=145|OwnerPartId=-1|LineWidth=1|Color=8388608|LocationCount=4|X1=880|Y1=350|X2=870|Y2=350|X3=870|Y3=340|X4=840|Y4=340
|RECORD=27|IndexInSheet=146|OwnerPartId=-1|LineWidth=1|Color=8388608|LocationCount=2|X1=880|Y1=370|X2=840|Y2=370
|RECORD=27|IndexInSheet=147|OwnerPartId=-1|LineWidth=1|Color=8388608|LocationCount=4|X1=880|Y1=380|X2=870|Y2=380|X3=870|Y3=400|X4=840|Y4=400
|RECORD=27|IndexInSheet=148|OwnerPartId=-1|LineWidth=1|Color=8388608|LocationCount=3|X1=880|Y1=390|X2=880|Y2=430|X3=840|Y3=430
|RECORD=27|IndexInSheet=149|OwnerPartId=-1|LineWidth=1|Color=8388608|LocationCount=2|X1=880|Y1=180|X2=870|Y2=180
|RECORD=27|IndexInSheet=150|OwnerPartId=-1|LineWidth=1|Color=8388608|LocationCount=3|X1=890|Y1=250|X2=890|Y2=260|X3=900|Y3=260
|RECORD=27|IndexInSheet=151|OwnerPartId=-1|LineWidth=1|Color=8388608|LocationCount=3|X1=910|Y1=170|X2=910|Y2=180|X3=900|Y3=180
|RECORD=27|IndexInSheet=152|OwnerPartId=-1|LineWidth=1|Color=8388608|LocationCount=2|X1=920|Y1=640|X2=940|Y2=640
|RECORD=27|IndexInSheet=153|OwnerPartId=-1|LineWidth=1|Color=8388608|LocationCount=2|X1=920|Y1=650|X2=1080|Y2=650
|RECORD=27|IndexInSheet=154|OwnerPartId=-1|LineWidth=1|Color=8388608|LocationCount=2|X1=920|Y1=660|X2=1040|Y2=660
|RECORD=27|IndexInSheet=155|OwnerPartId=-1|LineWidth=1|Color=8388608|LocationCount=2|X1=920|Y1=670|X2=940|Y2=670
|RECORD=27|IndexInSheet=156|OwnerPartId=-1|LineWidth=1|Color=8388608|LocationCount=2|X1=920|Y1=680|X2=940|Y2=680
|RECORD=27|IndexInSheet=157|OwnerPartId=-1|LineWidth=1|Color=8388608|LocationCount=2|X1=920|Y1=690|X2=1080|Y2=690
|RECORD=27|IndexInSheet=158|OwnerPartId=-1|LineWidth=1|Color=8388608|LocationCount=2|X1=920|Y1=700|X2=1040|Y2=700
|RECORD=27|IndexInSheet=159|OwnerPartId=-1|LineWidth=1|Color=8388608|LocationCount=2|X1=920|Y1=710|X2=940|Y2=710
|RECORD=27|IndexInSheet=160|OwnerPartId=-1|LineWidth=1|Color=8388608|LocationCount=2|X1=920|Y1=720|X2=940|Y2=720
|RECORD=27|IndexInSheet=161|OwnerPartId=-1|LineWidth=1|Color=8388608|LocationCount=2|X1=920|Y1=730|X2=1080|Y2=730
|RECORD=27|IndexInSheet=162|OwnerPartId=-1|LineWidth=1|Color=8388608|LocationCount=2|X1=920|Y1=740|X2=1040|Y2=740
|RECORD=27|IndexInSheet=163|OwnerPartId=-1|LineWidth=1|Color=8388608|LocationCount=2|X1=920|Y1=750|X2=940|Y2=750
|RECORD=27|IndexInSheet=164|OwnerPartId=-1|LineWidth=1|Color=8388608|LocationCount=2|X1=920|Y1=770|X2=940|Y2=770
|RECORD=27|IndexInSheet=165|OwnerPartId=-1|LineWidth=1|Color=8388608|LocationCount=2|X1=920|Y1=780|X2=1080|Y2=780
|RECORD=27|IndexInSheet=166|OwnerPartId=-1|LineWidth=1|Color=8388608|LocationCount=2|X1=920|Y1=790|X2=1010|Y2=790
|RECORD=27|IndexInSheet=167|OwnerPartId=-1|LineWidth=1|Color=8388608|LocationCount=2|X1=920|Y1=800|X2=940|Y2=800
|RECORD=27|IndexInSheet=168|OwnerPartId=-1|LineWidth=1|Color=8388608|LocationCount=2|X1=920|Y1=810|X2=1080|Y2=810
|RECORD=27|IndexInSheet=169|OwnerPartId=-1|LineWidth=1|Color=8388608|LocationCount=2|X1=920|Y1=820|X2=1040|Y2=820
|RECORD=27|IndexInSheet=170|OwnerPartId=-1|LineWidth=1|Color=8388608|LocationCount=2|X1=920|Y1=830|X2=940|Y2=830
|RECORD=27|IndexInSheet=171|OwnerPartId=-1|LineWidth=1|Color=8388608|LocationCount=3|X1=920|Y1=850|X2=1060|Y2=850|X3=1060|Y3=860
|RECORD=27|IndexInSheet=172|OwnerPartId=-1|LineWidth=1|Color=8388608|LocationCount=3|X1=920|Y1=860|X2=1030|Y2=860|X3=1030|Y3=870
|RECORD=27|IndexInSheet=173|OwnerPartId=-1|LineWidth=1|Color=8388608|LocationCount=3|X1=920|Y1=870|X2=1030|Y2=870|X3=1030|Y3=940
|RECORD=27|IndexInSheet=174|OwnerPartId=-1|LineWidth=1|Color=8388608|LocationCount=12|X1=920|Y1=920|X2=940|Y2=920|X3=940|Y3=830|X4=940|Y4=800|X5=940|Y5=770|X6=940|Y6=750|X7=940|Y7=720|X8=940|Y8=710|X9=940|Y9=680|X10=940|Y10=670|X11=940|Y11=640|X12=940|Y12=600
|RECORD=27|IndexInSheet=175|OwnerPartId=-1|LineWidth=1|Color=8388608|LocationCount=3|X1=920|Y1=930|X2=990|Y2=930|X3=990|Y3=940
|RECORD=27|IndexInSheet=176|OwnerPartId=-1|LineWidth=1|Color=8388608|LocationCount=3|X1=920|Y1=940|X2=990|Y2=940|X3=990|Y3=970
|RECORD=27|IndexInSheet=177|OwnerPartId=-1|LineWidth=1|Color=8388608|LocationCount=2|X1=920|Y1=950|X2=980|Y2=950
|RECORD=27|IndexInSheet=178|OwnerPartId=-1|LineWidth=1|Color=8388608|LocationCount=2|X1=980|Y1=350|X2=1010|Y2=350
|RECORD=27|IndexInSheet=179|OwnerPartId=-1|LineWidth=1|Color=8388608|LocationCount=4|X1=980|Y1=370|X2=1030|Y2=370|X3=1030|Y3=380|X4=1030|Y4=410
|RECORD=27|IndexInSheet=180|OwnerPartId=-1|LineWidth=1|Color=8388608|LocationCount=2|X1=980|Y1=380|X2=1030|Y2=380
|RECORD=27|IndexInSheet=181|OwnerPartId=-1|LineWidth=1|Color=8388608|LocationCount=4|X1=980|Y1=390|X2=1010|Y2=390|X3=1010|Y3=350|X4=1010|Y4=330
|RECORD=27|IndexInSheet=182|OwnerPartId=-1|LineWidth=1|Color=8388608|LocationCount=2|X1=1010|Y1=180|X2=1020|Y2=180
|RECORD=27|IndexInSheet=183|OwnerPartId=-1|LineWidth=1|Color=8388608|LocationCount=3|X1=1030|Y1=250|X2=1030|Y2=260|X3=1040|Y3=260
|RECORD=27|IndexInSheet=184|OwnerPartId=-1|LineWidth=1|Color=8388608|LocationCount=3|X1=1040|Y1=180|X2=1050|Y2=180|X3=1050|Y3=170
|RECORD=27|IndexInSheet=185|OwnerPartId=-1|LineWidth=1|Color=8388608|LocationCount=2|X1=1040|Y1=790|X2=1190|Y2=790
|RECORD=27|IndexInSheet=186|OwnerPartId=-1|LineWidth=1|Color=8388608|LocationCount=2|X1=1060|Y1=850|X2=1190|Y2=850
|RECORD=27|IndexInSheet=187|OwnerPartId=-1|LineWidth=1|Color=8388608|LocationCount=2|X1=1070|Y1=660|X2=1190|Y2=660
|RECORD=27|IndexInSheet=188|OwnerPartId=-1|LineWidth=1|Color=8388608|LocationCount=2|X1=1070|Y1=700|X2=1190|Y2=700
|RECORD=27|IndexInSheet=189|OwnerPartId=-1|LineWidth=1|Color=8388608|LocationCount=2|X1=1070|Y1=740|X2=1190|Y2=740
|RECORD=27|IndexInSheet=190|OwnerPartId=-1|LineWidth=1|Color=8388608|LocationCount=2|X1=1070|Y1=820|X2=1190|Y2=820
|RECORD=27|IndexInSheet=191|OwnerPartId=-1|LineWidth=1|Color=8388608|LocationCount=2|X1=1110|Y1=650|X2=1190|Y2=650
|RECORD=27|IndexInSheet=192|OwnerPartId=-1|LineWidth=1|Color=8388608|LocationCount=2|X1=1110|Y1=690|X2=1190|Y2=690
|RECORD=27|IndexInSheet=193|OwnerPartId=-1|LineWidth=1|Color=8388608|LocationCount=2|X1=1110|Y1=730|X2=1190|Y2=730
|RECORD=27|IndexInSheet=194|OwnerPartId=-1|LineWidth=1|Color=8388608|LocationCount=2|X1=1110|Y1=780|X2=1190|Y2=780
|RECORD=27|IndexInSheet=195|OwnerPartId=-1|LineWidth=1|Color=8388608|LocationCount=2|X1=1110|Y1=810|X2=1190|Y2=810
|RECORD=27|IndexInSheet=196|OwnerPartId=-1|LineWidth=1|Color=8388608|LocationCount=2|X1=1060|Y1=910|X2=1060|Y2=920
|RECORD=41|IndexInSheet=197|OwnerPartId=-1|Color=8388608|FontID=1|IsHidden=T|Name=ConfigurationParameters|ReadOnlyState=1
|RECORD=41|IndexInSheet=198|OwnerPartId=-1|Color=8388608|FontID=1|IsHidden=T|Name=ConfiguratorName|ReadOnlyState=1
|RECORD=41|IndexInSheet=199|OwnerPartId=-1|Color=8388608|FontID=1|IsHidden=T|Name=VersionControl_RevNumber|ReadOnlyState=1
|RECORD=41|IndexInSheet=200|OwnerPartId=-1|Color=8388608|FontID=1|IsHidden=T|Name=IsUserConfigurable|ReadOnlyState=1
|RECORD=41|IndexInSheet=201|OwnerPartId=-1|Color=8388608|FontID=1|IsHidden=T|Name=VersionControl_ProjFolderRevNumber|ReadOnlyState=1
|RECORD=41|IndexInSheet=202|OwnerPartId=-1|Color=8388608|FontID=1|IsHidden=T|Name=SPICEModelCache|ReadOnlyState=1
|RECORD=29|IndexInSheet=-1|OwnerPartId=-1|Location.X=670|Location.Y=940|Color=128
|RECORD=29|IndexInSheet=-1|OwnerPartId=-1|Location.X=670|Location.Y=950|Color=128
|RECORD=29|IndexInSheet=-1|OwnerPartId=-1|Location.X=740|Location.Y=630|Color=128
|RECORD=29|IndexInSheet=-1|OwnerPartId=-1|Location.X=740|Location.Y=660|Color=128
|RECORD=29|IndexInSheet=-1|OwnerPartId=-1|Location.X=740|Location.Y=690|Color=128
|RECORD=29|IndexInSheet=-1|OwnerPartId=-1|Location.X=740|Location.Y=700|Color=128
|RECORD=29|IndexInSheet=-1|OwnerPartId=-1|Location.X=740|Location.Y=730|Color=128
|RECORD=29|IndexInSheet=-1|OwnerPartId=-1|Location.X=740|Location.Y=740|Color=128
|RECORD=29|IndexInSheet=-1|OwnerPartId=-1|Location.X=740|Location.Y=770|Color=128
|RECORD=29|IndexInSheet=-1|OwnerPartId=-1|Location.X=740|Location.Y=790|Color=128
|RECORD=29|IndexInSheet=-1|OwnerPartId=-1|Location.X=740|Location.Y=820|Color=128
|RECORD=29|IndexInSheet=-1|OwnerPartId=-1|Location.X=740|Location.Y=890|Color=128
|RECORD=29|IndexInSheet=-1|OwnerPartId=-1|Location.X=940|Location.Y=640|Color=128
|RECORD=29|IndexInSheet=-1|OwnerPartId=-1|Location.X=940|Location.Y=670|Color=128
|RECORD=29|IndexInSheet=-1|OwnerPartId=-1|Location.X=940|Location.Y=680|Color=128
|RECORD=29|IndexInSheet=-1|OwnerPartId=-1|Location.X=940|Location.Y=710|Color=128
|RECORD=29|IndexInSheet=-1|OwnerPartId=-1|Location.X=940|Location.Y=720|Color=128
|RECORD=29|IndexInSheet=-1|OwnerPartId=-1|Location.X=940|Location.Y=750|Color=128
|RECORD=29|IndexInSheet=-1|OwnerPartId=-1|Location.X=940|Location.Y=770|Color=128
|RECORD=29|IndexInSheet=-1|OwnerPartId=-1|Location.X=940|Location.Y=800|Color=128
|RECORD=29|IndexInSheet=-1|OwnerPartId=-1|Location.X=940|Location.Y=830|Color=128
|RECORD=29|IndexInSheet=-1|OwnerPartId=-1|Location.X=990|Location.Y=940|Color=128
|RECORD=29|IndexInSheet=-1|OwnerPartId=-1|Location.X=1010|Location.Y=350|Color=128
|RECORD=29|IndexInSheet=-1|OwnerPartId=-1|Location.X=1030|Location.Y=380|Color=128
|RECORD=29|IndexInSheet=-1|OwnerPartId=-1|Location.X=1030|Location.Y=870|Color=128
|RECORD=29|IndexInSheet=-1|OwnerPartId=-1|Location.X=1060|Location.Y=850|Color=128